%FSTAX23Y23*%
%MOIN*%
%SFA1B1*%

%IPPOS*%
%AMD38*
4,1,8,-0.010500,0.010000,-0.010500,-0.010000,0.000000,-0.020400,0.000000,-0.020400,0.010500,-0.010000,0.010500,0.010000,0.000000,0.020400,0.000000,0.020400,-0.010500,0.010000,0.0*
1,1,0.020960,0.000000,0.010000*
1,1,0.020960,0.000000,-0.010000*
1,1,0.020960,0.000000,-0.010000*
1,1,0.020960,0.000000,0.010000*
%
%ADD26R,0.028000X0.165000*%
%ADD27R,0.028000X0.126000*%
%ADD28R,0.028350X0.039370*%
%ADD29R,0.027560X0.035430*%
%ADD30R,0.086610X0.041340*%
%ADD31R,0.041340X0.039370*%
%ADD32R,0.037400X0.031500*%
%ADD33R,0.057090X0.045280*%
%ADD34R,0.212600X0.114170*%
%ADD35R,0.041340X0.043310*%
%ADD36R,0.029530X0.033470*%
%ADD37R,0.043310X0.041340*%
G04~CAMADD=38~8~0.0~0.0~408.8~209.5~104.8~0.0~15~0.0~0.0~0.0~0.0~0~0.0~0.0~0.0~0.0~0~0.0~0.0~0.0~90.0~210.0~409.0*
%ADD38D38*%
%ADD39R,0.020950X0.040880*%
%ADD40R,0.035430X0.039370*%
%ADD41R,0.037400X0.033470*%
%ADD42R,0.009840X0.061020*%
%ADD43R,0.066930X0.053150*%
%ADD44R,0.053150X0.066930*%
%ADD45R,0.061020X0.009840*%
%ADD46O,0.078740X0.023620*%
%ADD47R,0.064960X0.051180*%
%ADD48R,0.017720X0.054330*%
%ADD49R,0.055910X0.061020*%
%ADD50R,0.070870X0.074800*%
%ADD51R,0.039370X0.074800*%
%ADD52R,0.019680X0.090550*%
%ADD53R,0.078740X0.098430*%
%ADD54R,0.019680X0.035430*%
%ADD55O,0.057090X0.017720*%
%ADD56R,0.077560X0.022440*%
%ADD57R,0.025590X0.041340*%
%ADD58R,0.051180X0.074800*%
%ADD59R,0.039370X0.090550*%
%ADD60R,0.039370X0.070870*%
%ADD61R,0.053150X0.027560*%
%ADD62R,0.027560X0.045280*%
%ADD63R,0.041340X0.045280*%
%ADD64R,0.050000X0.200000*%
%ADD65R,0.057090X0.037400*%
%ADD66R,0.031500X0.066930*%
%ADD67R,0.070870X0.009840*%
%ADD68R,0.009840X0.022640*%
%ADD69R,0.026570X0.009840*%
%ADD70R,0.038580X0.034250*%
%ADD71R,0.165350X0.125980*%
%ADD72R,0.096460X0.124020*%
%ADD73R,0.033470X0.039370*%
%ADD74R,0.037400X0.039370*%
%ADD75R,0.009840X0.010830*%
%ADD76R,0.010830X0.009840*%
%ADD77R,0.045280X0.057090*%
%ADD78R,0.039370X0.033470*%
%ADD79R,0.039370X0.028350*%
%ADD80R,0.023620X0.025590*%
%ADD81R,0.082870X0.044090*%
%ADD82R,0.039370X0.037400*%
%ADD83R,0.035430X0.027560*%
%LNtimingcard_pcb-1*%
%LPD*%
G36*
X06791Y01176D02*
X06797D01*
Y01176*
X068*
Y01175*
X06802*
Y01175*
X06803*
Y01174*
X06804*
Y01174*
X06805*
Y01173*
X06807*
Y01173*
X06808*
Y01172*
X06809*
Y01172*
X0681*
Y01171*
X0681*
Y01171*
X06811*
Y0117*
X06812*
Y01169*
X06813*
Y01169*
X06814*
Y01168*
X06814*
Y01168*
X06815*
Y01167*
X06815*
Y01167*
X06816*
Y01166*
X06816*
Y01166*
X06817*
Y01165*
X06817*
Y01165*
X06818*
Y01164*
X06818*
Y01163*
X06819*
Y01163*
Y01162*
X0682*
Y01162*
X0682*
Y01161*
Y01161*
X06821*
Y0116*
X06821*
Y0116*
Y01159*
X06822*
Y01159*
Y01158*
X06822*
Y01158*
X06823*
Y01157*
Y01156*
X06823*
Y01156*
Y01155*
Y01155*
X06824*
Y01154*
Y01154*
X06824*
Y01153*
Y01153*
Y01152*
X06825*
Y01152*
Y01151*
Y01151*
Y0115*
X06825*
Y01149*
Y01149*
Y01148*
Y01148*
X06826*
Y01147*
Y01147*
Y01146*
Y01146*
Y01145*
Y01145*
Y01144*
Y01143*
Y01143*
Y01142*
X06827*
Y01142*
Y01141*
Y01141*
Y0114*
X06826*
Y0114*
Y01139*
Y01139*
Y01138*
Y01138*
Y01137*
Y01136*
Y01136*
Y01135*
X06825*
Y01135*
Y01134*
Y01134*
Y01133*
Y01133*
X06825*
Y01132*
Y01132*
Y01131*
X06824*
Y01131*
Y0113*
Y01129*
X06824*
Y01129*
Y01128*
Y01128*
X06823*
Y01127*
Y01127*
X06823*
Y01126*
Y01126*
X06822*
Y01125*
Y01125*
X06822*
Y01124*
Y01123*
X06821*
Y01123*
Y01122*
X06821*
Y01122*
X0682*
Y01121*
Y01121*
X0682*
Y0112*
X06819*
Y0112*
X06818*
Y01119*
Y01119*
X06818*
Y01118*
X06817*
Y01118*
X06817*
Y01117*
X06816*
Y01116*
X06816*
Y01116*
X06815*
Y01115*
X06815*
Y01115*
X06814*
Y01114*
X06813*
Y01114*
X06813*
Y01113*
X06812*
Y01113*
X06811*
Y01112*
X0681*
Y01112*
X0681*
Y01111*
X06809*
Y01111*
X06808*
Y0111*
X06807*
Y01109*
X06805*
Y01109*
X06804*
Y01108*
X06803*
Y01108*
X06801*
Y01107*
X06799*
Y01107*
X06796*
Y01106*
X06744*
Y01107*
X06741*
Y01107*
X0674*
Y01108*
X06738*
Y01108*
X06736*
Y01109*
X06735*
Y01109*
X06734*
Y0111*
X06733*
Y01111*
X06732*
Y01111*
X06731*
Y01112*
X0673*
Y01112*
X06729*
Y01113*
X06729*
Y01113*
X06728*
Y01114*
X06727*
Y01114*
X06727*
Y01115*
X06726*
Y01115*
X06725*
Y01116*
X06725*
Y01116*
X06724*
Y01117*
X06724*
Y01118*
X06723*
Y01118*
X06723*
Y01119*
X06722*
Y01119*
X06722*
Y0112*
Y0112*
X06721*
Y01121*
X06721*
Y01121*
X0672*
Y01122*
Y01122*
X0672*
Y01123*
Y01123*
X06719*
Y01124*
X06718*
Y01125*
Y01125*
X06718*
Y01126*
Y01126*
X06717*
Y01127*
Y01127*
X06717*
Y01128*
Y01128*
Y01129*
X06716*
Y01129*
Y0113*
Y01131*
X06716*
Y01131*
Y01132*
Y01132*
X06715*
Y01133*
Y01133*
Y01134*
Y01134*
Y01135*
X06715*
Y01135*
Y01136*
Y01136*
Y01137*
Y01138*
X06714*
Y01138*
Y01139*
Y01139*
Y0114*
Y0114*
Y01141*
Y01141*
Y01142*
Y01142*
Y01143*
Y01143*
Y01144*
Y01145*
X06715*
Y01145*
Y01146*
Y01146*
Y01147*
Y01147*
Y01148*
Y01148*
X06715*
Y01149*
Y01149*
Y0115*
Y01151*
X06716*
Y01151*
Y01152*
Y01152*
Y01153*
X06716*
Y01153*
Y01154*
X06717*
Y01154*
Y01155*
Y01155*
X06717*
Y01156*
Y01156*
X06718*
Y01157*
Y01158*
X06718*
Y01158*
Y01159*
X06719*
Y01159*
Y0116*
X0672*
Y0116*
X0672*
Y01161*
Y01161*
X06721*
Y01162*
X06721*
Y01162*
Y01163*
X06722*
Y01163*
X06722*
Y01164*
X06723*
Y01165*
X06723*
Y01165*
X06724*
Y01166*
X06724*
Y01166*
X06725*
Y01167*
X06725*
Y01167*
X06726*
Y01168*
X06727*
Y01168*
X06727*
Y01169*
X06728*
Y01169*
X06728*
Y0117*
X06729*
Y01171*
X0673*
Y01171*
X06731*
Y01172*
X06731*
Y01172*
X06732*
Y01173*
X06734*
Y01173*
X06735*
Y01174*
X06736*
Y01174*
X06737*
Y01175*
X06739*
Y01175*
X06741*
Y01176*
X06743*
Y01176*
X06749*
Y01177*
X0679*
Y01176*
X06791*
Y01177*
X06791*
Y01176*
G37*
G36*
X05972Y0095D02*
X05975D01*
Y0095*
X05976*
Y00949*
X05977*
Y00949*
X05978*
Y00948*
X05979*
Y00948*
X0598*
Y00947*
X0598*
Y00947*
X05982*
Y00946*
X05982*
Y00946*
X05983*
Y00945*
X05983*
Y00945*
X05984*
Y00944*
X05984*
Y00943*
Y00943*
X05985*
Y00942*
X05985*
Y00942*
Y00941*
X05986*
Y00941*
X05986*
Y0094*
Y0094*
X05987*
Y00939*
Y00939*
Y00938*
X05988*
Y00938*
Y00937*
Y00936*
X05988*
Y00936*
Y00935*
Y00935*
Y00934*
X05989*
Y00934*
Y00933*
Y00933*
Y00932*
Y00932*
Y00931*
Y0093*
Y0093*
Y00929*
Y00929*
Y00928*
Y00928*
Y00927*
X05988*
Y00927*
Y00926*
Y00926*
Y00925*
X05988*
Y00925*
Y00924*
Y00923*
X05987*
Y00923*
Y00922*
X05986*
Y00922*
Y00921*
X05986*
Y00921*
Y0092*
X05985*
Y0092*
X05985*
Y00919*
Y00919*
X05984*
Y00918*
X05984*
Y00918*
X05983*
Y00917*
X05983*
Y00916*
X05982*
Y00916*
X05982*
Y00915*
X05981*
Y00915*
X0598*
Y00914*
X05979*
Y00914*
X05979*
Y00913*
X05978*
Y00913*
X05977*
Y00912*
X05975*
Y00912*
X05973*
Y00911*
X0597*
Y0091*
X05966*
Y00911*
X05963*
Y00912*
X05962*
Y00912*
X0596*
Y00913*
X05959*
Y00913*
X05958*
Y00914*
X05957*
Y00914*
X05957*
Y00915*
X05956*
Y00915*
X05955*
Y00916*
X05955*
Y00916*
X05954*
Y00917*
X05953*
Y00918*
X05953*
Y00918*
X05952*
Y00919*
X05952*
Y00919*
Y0092*
X05951*
Y0092*
Y00921*
X05951*
Y00921*
X0595*
Y00922*
Y00922*
X0595*
Y00923*
Y00923*
Y00924*
X05949*
Y00925*
Y00925*
Y00926*
X05949*
Y00926*
Y00927*
Y00927*
Y00928*
Y00928*
X05948*
Y00929*
Y00929*
Y0093*
Y0093*
Y00931*
Y00932*
Y00932*
Y00933*
Y00933*
Y00934*
X05949*
Y00934*
Y00935*
Y00935*
Y00936*
Y00936*
X05949*
Y00937*
Y00938*
Y00938*
X0595*
Y00939*
Y00939*
X0595*
Y0094*
Y0094*
X05951*
Y00941*
Y00941*
X05951*
Y00942*
Y00942*
X05952*
Y00943*
X05952*
Y00943*
X05953*
Y00944*
Y00945*
X05953*
Y00945*
X05954*
Y00946*
X05955*
Y00946*
X05956*
Y00947*
X05956*
Y00947*
X05957*
Y00948*
X05958*
Y00948*
X05958*
Y00949*
X05959*
Y00949*
X05961*
Y0095*
X05962*
Y0095*
X05964*
Y00951*
X05972*
Y0095*
G37*
G36*
X05972Y00877D02*
X05974D01*
Y00877*
X05976*
Y00876*
X05977*
Y00876*
X05978*
Y00875*
X05979*
Y00875*
X0598*
Y00874*
X0598*
Y00874*
X05981*
Y00873*
X05982*
Y00873*
X05983*
Y00872*
X05983*
Y00872*
X05984*
Y00871*
Y0087*
X05984*
Y0087*
X05985*
Y00869*
X05985*
Y00869*
Y00868*
X05986*
Y00868*
Y00867*
X05986*
Y00867*
Y00866*
X05987*
Y00866*
Y00865*
X05988*
Y00865*
Y00864*
Y00863*
X05988*
Y00863*
Y00862*
Y00862*
Y00861*
X05989*
Y00861*
Y0086*
Y0086*
Y00859*
Y00859*
Y00858*
Y00857*
Y00857*
Y00856*
Y00856*
Y00855*
Y00855*
Y00854*
X05988*
Y00854*
Y00853*
Y00853*
Y00852*
X05988*
Y00852*
Y00851*
Y0085*
X05987*
Y0085*
Y00849*
X05986*
Y00849*
Y00848*
X05986*
Y00848*
Y00847*
X05985*
Y00847*
Y00846*
X05985*
Y00846*
X05984*
Y00845*
X05984*
Y00845*
Y00844*
X05983*
Y00843*
X05983*
Y00843*
X05982*
Y00842*
X05981*
Y00842*
X0598*
Y00841*
X0598*
Y00841*
X05979*
Y0084*
X05978*
Y0084*
X05977*
Y00839*
X05976*
Y00839*
X05974*
Y00838*
X05971*
Y00837*
X05965*
Y00838*
X05963*
Y00839*
X05961*
Y00839*
X0596*
Y0084*
X05959*
Y0084*
X05958*
Y00841*
X05957*
Y00841*
X05956*
Y00842*
X05956*
Y00842*
X05955*
Y00843*
X05955*
Y00843*
X05954*
Y00844*
X05953*
Y00845*
X05953*
Y00845*
X05952*
Y00846*
X05952*
Y00846*
Y00847*
X05951*
Y00847*
X05951*
Y00848*
Y00848*
X0595*
Y00849*
Y00849*
X0595*
Y0085*
Y0085*
Y00851*
X05949*
Y00852*
Y00852*
Y00853*
X05949*
Y00853*
Y00854*
Y00854*
Y00855*
X05948*
Y00855*
Y00856*
Y00856*
Y00857*
Y00857*
Y00858*
Y00859*
Y00859*
Y0086*
Y0086*
Y00861*
X05949*
Y00861*
Y00862*
Y00862*
Y00863*
X05949*
Y00863*
Y00864*
Y00865*
Y00865*
X0595*
Y00866*
Y00866*
X0595*
Y00867*
Y00867*
X05951*
Y00868*
Y00868*
X05951*
Y00869*
X05952*
Y00869*
Y0087*
X05952*
Y0087*
X05953*
Y00871*
X05953*
Y00872*
X05954*
Y00872*
X05955*
Y00873*
X05955*
Y00873*
X05956*
Y00874*
X05956*
Y00874*
X05957*
Y00875*
X05958*
Y00875*
X05959*
Y00876*
X0596*
Y00876*
X05961*
Y00877*
X05963*
Y00877*
X05965*
Y00878*
X05972*
Y00877*
G37*
G36*
X06916Y00894D02*
X06919D01*
Y00894*
X06921*
Y00893*
X06923*
Y00893*
X06924*
Y00892*
X06925*
Y00892*
X06927*
Y00891*
X06928*
Y0089*
X06929*
Y0089*
X0693*
Y00889*
X06931*
Y00889*
X06931*
Y00888*
X06933*
Y00888*
X06933*
Y00887*
X06934*
Y00887*
X06934*
Y00886*
X06935*
Y00886*
X06936*
Y00885*
X06936*
Y00885*
X06937*
Y00884*
X06937*
Y00883*
X06938*
Y00883*
X06938*
Y00882*
X06939*
Y00882*
Y00881*
X0694*
Y00881*
X0694*
Y0088*
X06941*
Y0088*
Y00879*
X06941*
Y00879*
X06942*
Y00878*
Y00877*
X06942*
Y00877*
Y00876*
X06943*
Y00876*
X06943*
Y00875*
Y00875*
X06944*
Y00874*
Y00874*
Y00873*
X06944*
Y00873*
Y00872*
X06945*
Y00872*
Y00871*
Y0087*
X06945*
Y0087*
Y00869*
Y00869*
X06946*
Y00868*
Y00868*
Y00867*
Y00867*
X06947*
Y00866*
Y00866*
Y00865*
Y00865*
Y00864*
Y00863*
X06947*
Y00863*
Y00862*
Y00862*
Y00861*
Y00861*
Y0086*
Y0086*
Y00859*
Y00859*
Y00858*
Y00857*
Y00857*
Y00856*
Y00856*
Y00855*
X06947*
Y00855*
Y00854*
Y00854*
Y00853*
Y00853*
Y00852*
X06946*
Y00852*
Y00851*
Y0085*
Y0085*
X06945*
Y00849*
Y00849*
Y00848*
X06945*
Y00848*
Y00847*
Y00847*
X06944*
Y00846*
Y00846*
X06944*
Y00845*
Y00845*
X06943*
Y00844*
Y00843*
X06943*
Y00843*
Y00842*
X06942*
Y00842*
Y00841*
X06942*
Y00841*
X06941*
Y0084*
Y0084*
X06941*
Y00839*
X0694*
Y00839*
Y00838*
X0694*
Y00837*
X06939*
Y00837*
X06938*
Y00836*
X06938*
Y00836*
X06937*
Y00835*
X06937*
Y00835*
X06936*
Y00834*
X06936*
Y00834*
X06935*
Y00833*
X06935*
Y00833*
X06934*
Y00832*
X06934*
Y00832*
X06933*
Y00831*
X06932*
Y0083*
X06931*
Y0083*
X0693*
Y00829*
X06929*
Y00829*
X06929*
Y00828*
X06928*
Y00828*
X06927*
Y00827*
X06925*
Y00827*
X06924*
Y00826*
X06922*
Y00826*
X0692*
Y00825*
X06917*
Y00825*
X06914*
Y00824*
X06914*
Y00825*
X06913*
Y00824*
X06913*
Y00825*
X06912*
Y00824*
X06908*
Y00825*
X06904*
Y00825*
X06902*
Y00826*
X069*
Y00826*
X06898*
Y00827*
X06897*
Y00827*
X06896*
Y00828*
X06895*
Y00828*
X06894*
Y00829*
X06893*
Y00829*
X06892*
Y0083*
X06891*
Y0083*
X0689*
Y00831*
X06889*
Y00832*
X06889*
Y00832*
X06888*
Y00833*
X06888*
Y00833*
X06887*
Y00834*
X06886*
Y00834*
X06885*
Y00835*
X06885*
Y00835*
X06884*
Y00836*
X06884*
Y00836*
Y00837*
X06883*
Y00837*
X06883*
Y00838*
X06882*
Y00839*
X06882*
Y00839*
Y0084*
X06881*
Y0084*
X06881*
Y00841*
Y00841*
X0688*
Y00842*
Y00842*
X0688*
Y00843*
X06879*
Y00843*
Y00844*
X06878*
Y00845*
Y00845*
X06878*
Y00846*
Y00846*
Y00847*
X06877*
Y00847*
Y00848*
X06877*
Y00848*
Y00849*
Y00849*
X06876*
Y0085*
Y0085*
Y00851*
Y00852*
X06876*
Y00852*
Y00853*
Y00853*
Y00854*
Y00854*
X06875*
Y00855*
Y00855*
Y00856*
Y00856*
Y00857*
Y00857*
Y00858*
Y00859*
Y00859*
Y0086*
Y0086*
Y00861*
Y00861*
Y00862*
Y00862*
Y00863*
Y00863*
Y00864*
Y00865*
X06876*
Y00865*
Y00866*
Y00866*
Y00867*
Y00867*
X06876*
Y00868*
Y00868*
Y00869*
Y00869*
X06877*
Y0087*
Y0087*
Y00871*
X06877*
Y00872*
Y00872*
Y00873*
X06878*
Y00873*
Y00874*
X06878*
Y00874*
Y00875*
X06879*
Y00875*
Y00876*
X0688*
Y00876*
Y00877*
X0688*
Y00877*
Y00878*
X06881*
Y00879*
X06881*
Y00879*
Y0088*
X06882*
Y0088*
X06882*
Y00881*
X06883*
Y00881*
Y00882*
X06883*
Y00882*
X06884*
Y00883*
X06884*
Y00883*
X06885*
Y00884*
X06885*
Y00885*
X06886*
Y00885*
X06887*
Y00886*
X06887*
Y00886*
X06888*
Y00887*
X06888*
Y00887*
X06889*
Y00888*
X0689*
Y00888*
X06891*
Y00889*
X06891*
Y00889*
X06893*
Y0089*
X06893*
Y0089*
X06894*
Y00891*
X06895*
Y00892*
X06896*
Y00892*
X06898*
Y00893*
X069*
Y00893*
X06901*
Y00894*
X06903*
Y00894*
X06906*
Y00895*
X06916*
Y00894*
G37*
G36*
X06629Y01176D02*
X06635D01*
Y01176*
X06637*
Y01175*
X06639*
Y01175*
X06641*
Y01174*
X06642*
Y01174*
X06643*
Y01173*
X06644*
Y01173*
X06645*
Y01172*
X06647*
Y01172*
X06648*
Y01171*
X06648*
Y01171*
X06649*
Y0117*
X0665*
Y01169*
X0665*
Y01169*
X06651*
Y01168*
X06652*
Y01168*
X06652*
Y01167*
X06653*
Y01167*
X06654*
Y01166*
X06654*
Y01166*
X06655*
Y01165*
X06655*
Y01165*
X06656*
Y01164*
X06656*
Y01163*
X06657*
Y01163*
Y01162*
X06657*
Y01162*
X06658*
Y01161*
X06658*
Y01161*
Y0116*
X06659*
Y0116*
Y01159*
X0666*
Y01159*
X0666*
Y01158*
Y01158*
X06661*
Y01157*
Y01156*
X06661*
Y01156*
Y01155*
X06662*
Y01155*
Y01154*
Y01154*
X06662*
Y01153*
Y01153*
Y01152*
X06663*
Y01152*
Y01151*
Y01151*
X06663*
Y0115*
Y01149*
Y01149*
Y01148*
X06664*
Y01148*
Y01147*
Y01147*
Y01146*
Y01146*
Y01145*
X06664*
Y01145*
Y01144*
Y01143*
Y01143*
Y01142*
Y01142*
Y01141*
Y01141*
Y0114*
Y0114*
Y01139*
X06664*
Y01139*
X06664*
Y01138*
X06664*
Y01138*
Y01137*
Y01136*
Y01136*
Y01135*
Y01135*
Y01134*
X06663*
Y01134*
Y01133*
Y01133*
Y01132*
X06663*
Y01132*
Y01131*
Y01131*
X06662*
Y0113*
Y01129*
Y01129*
X06662*
Y01128*
Y01128*
Y01127*
X06661*
Y01127*
Y01126*
X06661*
Y01126*
Y01125*
X0666*
Y01125*
Y01124*
X0666*
Y01123*
X06659*
Y01123*
Y01122*
X06658*
Y01122*
X06658*
Y01121*
Y01121*
X06657*
Y0112*
X06657*
Y0112*
X06656*
Y01119*
Y01119*
X06656*
Y01118*
X06655*
Y01118*
X06655*
Y01117*
X06654*
Y01116*
X06654*
Y01116*
X06653*
Y01115*
X06652*
Y01115*
X06652*
Y01114*
X06651*
Y01114*
X0665*
Y01113*
X0665*
Y01113*
X06649*
Y01112*
X06648*
Y01112*
X06647*
Y01111*
X06647*
Y01111*
X06645*
Y0111*
X06644*
Y01109*
X06643*
Y01109*
X06642*
Y01108*
X06641*
Y01108*
X06638*
Y01107*
X06637*
Y01107*
X06634*
Y01106*
X06552*
Y01106*
X06548*
Y01105*
X06545*
Y01105*
X06543*
Y01104*
X06542*
Y01103*
X06541*
Y01103*
X06539*
Y01102*
X06538*
Y01102*
X06537*
Y01101*
X06536*
Y01101*
X06536*
Y011*
X06535*
Y011*
X06534*
Y01099*
X06533*
Y01099*
X06532*
Y01098*
X06532*
Y01098*
X06531*
Y01097*
X0653*
Y01096*
X0653*
Y01096*
X06529*
Y01095*
X06529*
Y01095*
X06528*
Y01094*
X06528*
Y01094*
X06527*
Y01093*
Y01093*
X06527*
Y01092*
X06526*
Y01092*
X06525*
Y01091*
Y01091*
X06525*
Y0109*
X06524*
Y01089*
Y01089*
X06524*
Y01088*
X06523*
Y01088*
Y01087*
X06523*
Y01087*
Y01086*
X06522*
Y01086*
Y01085*
X06522*
Y01085*
Y01084*
Y01083*
X06521*
Y01083*
Y01082*
X06521*
Y01082*
Y01081*
Y01081*
X0652*
Y0108*
Y0108*
Y01079*
Y01079*
X06519*
Y01078*
Y01078*
Y01077*
Y01076*
Y01076*
Y01075*
X06519*
Y01075*
Y01074*
Y01074*
Y01073*
Y01073*
Y01072*
Y01072*
Y01071*
Y0107*
Y0107*
Y01069*
Y01069*
Y01068*
Y01068*
Y01067*
Y01067*
X06519*
Y01066*
Y01066*
Y01065*
Y01065*
Y01064*
Y01063*
X0652*
Y01063*
Y01062*
Y01062*
Y01061*
X06521*
Y01061*
Y0106*
Y0106*
X06521*
Y01059*
Y01059*
Y01058*
X06522*
Y01058*
Y01057*
X06522*
Y01056*
Y01056*
X06523*
Y01055*
Y01055*
X06523*
Y01054*
Y01054*
X06524*
Y01053*
Y01053*
X06524*
Y01052*
X06525*
Y01052*
Y01051*
X06525*
Y0105*
X06526*
Y0105*
Y01049*
X06527*
Y01049*
X06527*
Y01048*
X06528*
Y01048*
X06528*
Y01047*
X06529*
Y01047*
X06529*
Y01046*
X0653*
Y01046*
X0653*
Y01045*
X06531*
Y01045*
X06531*
Y01044*
X06532*
Y01043*
X06532*
Y01043*
X06534*
Y01042*
X06534*
Y01042*
X06535*
Y01041*
X06536*
Y01041*
X06537*
Y0104*
X06538*
Y0104*
X06539*
Y01039*
X0654*
Y01039*
X06541*
Y01038*
X06543*
Y01038*
X06544*
Y01037*
X06547*
Y01036*
X06549*
Y01036*
X06977*
Y01035*
X06977*
Y01036*
X06978*
Y01035*
X06982*
Y01035*
X06984*
Y01034*
X06986*
Y01034*
X06987*
Y01033*
X06989*
Y01033*
X0699*
Y01032*
X06991*
Y01032*
X06992*
Y01031*
X06993*
Y0103*
X06994*
Y0103*
X06995*
Y01029*
X06995*
Y01029*
X06996*
Y01028*
X06997*
Y01028*
X06997*
Y01027*
X06998*
Y01027*
X06999*
Y01026*
X07*
Y01026*
X07*
Y01025*
X07001*
Y01025*
X07001*
Y01024*
X07002*
Y01023*
Y01023*
X07002*
Y01022*
X07003*
Y01022*
X07003*
Y01021*
X07004*
Y01021*
Y0102*
X07004*
Y0102*
X07005*
Y01019*
Y01019*
X07006*
Y01018*
X07006*
Y01018*
Y01017*
X07007*
Y01016*
Y01016*
X07007*
Y01015*
Y01015*
X07008*
Y01014*
Y01014*
Y01013*
X07008*
Y01013*
Y01012*
X07009*
Y01012*
Y01011*
Y0101*
X07009*
Y0101*
Y01009*
Y01009*
Y01008*
X0701*
Y01008*
Y01007*
Y01007*
Y01006*
Y01006*
X0701*
Y01005*
Y01005*
Y01004*
Y01003*
Y01003*
Y01002*
Y01002*
Y01001*
Y01001*
Y01*
Y01*
Y00999*
Y00999*
Y00998*
Y00998*
Y00997*
Y00996*
Y00996*
Y00995*
X0701*
Y00995*
Y00994*
Y00994*
Y00993*
Y00993*
X07009*
Y00992*
Y00992*
Y00991*
Y0099*
X07009*
Y0099*
Y00989*
Y00989*
X07008*
Y00988*
Y00988*
Y00987*
X07008*
Y00987*
Y00986*
X07007*
Y00986*
Y00985*
X07007*
Y00985*
Y00984*
X07006*
Y00983*
Y00983*
X07006*
Y00982*
Y00982*
X07005*
Y00981*
X07004*
Y00981*
Y0098*
X07004*
Y0098*
X07003*
Y00979*
X07003*
Y00979*
X07002*
Y00978*
Y00978*
X07002*
Y00977*
X07001*
Y00976*
X07001*
Y00976*
X07*
Y00975*
X07*
Y00975*
X06999*
Y00974*
X06998*
Y00974*
X06998*
Y00973*
X06997*
Y00973*
X06996*
Y00972*
X06996*
Y00972*
X06995*
Y00971*
X06994*
Y0097*
X06993*
Y0097*
X06992*
Y00969*
X06991*
Y00969*
X0699*
Y00968*
X06989*
Y00968*
X06988*
Y00967*
X06986*
Y00967*
X06984*
Y00966*
X06982*
Y00966*
X06979*
Y00965*
X06698*
Y00965*
X06695*
Y00964*
X06693*
Y00963*
X06691*
Y00963*
X0669*
Y00962*
X06688*
Y00962*
X06687*
Y00961*
X06686*
Y00961*
X06685*
Y0096*
X06684*
Y0096*
X06683*
Y00959*
X06682*
Y00959*
X06682*
Y00958*
X06681*
Y00958*
X0668*
Y00957*
X0668*
Y00956*
X06679*
Y00956*
X06678*
Y00955*
X06678*
Y00955*
X06677*
Y00954*
X06677*
Y00954*
X06676*
Y00953*
X06676*
Y00953*
X06675*
Y00952*
X06675*
Y00952*
X06674*
Y00951*
Y0095*
X06674*
Y0095*
X06673*
Y00949*
Y00949*
X06672*
Y00948*
X06672*
Y00948*
Y00947*
X06671*
Y00947*
Y00946*
X06671*
Y00946*
Y00945*
X0667*
Y00945*
Y00944*
X0667*
Y00943*
Y00943*
X06669*
Y00942*
Y00942*
Y00941*
X06669*
Y00941*
Y0094*
Y0094*
X06668*
Y00939*
Y00939*
Y00938*
Y00938*
X06668*
Y00937*
Y00936*
Y00936*
Y00935*
Y00935*
Y00934*
X06667*
Y00934*
Y00933*
Y00933*
Y00932*
Y00932*
Y00931*
Y0093*
Y0093*
Y00929*
Y00929*
Y00928*
Y00928*
Y00927*
Y00927*
Y00926*
Y00926*
X06668*
Y00925*
Y00925*
Y00924*
Y00923*
Y00923*
Y00922*
X06668*
Y00922*
Y00921*
Y00921*
Y0092*
X06669*
Y0092*
Y00919*
Y00919*
X06669*
Y00918*
Y00918*
Y00917*
X0667*
Y00916*
Y00916*
X0667*
Y00915*
Y00915*
X06671*
Y00914*
Y00914*
X06671*
Y00913*
Y00913*
X06672*
Y00912*
Y00912*
X06672*
Y00911*
X06673*
Y0091*
Y0091*
X06674*
Y00909*
X06674*
Y00909*
X06675*
Y00908*
Y00908*
X06675*
Y00907*
X06676*
Y00907*
X06676*
Y00906*
X06677*
Y00906*
X06677*
Y00905*
X06678*
Y00905*
X06678*
Y00904*
X06679*
Y00903*
X0668*
Y00903*
X06681*
Y00902*
X06681*
Y00902*
X06682*
Y00901*
X06683*
Y00901*
X06683*
Y009*
X06684*
Y009*
X06685*
Y00899*
X06686*
Y00899*
X06687*
Y00898*
X06689*
Y00897*
X0669*
Y00897*
X06691*
Y00896*
X06693*
Y00896*
X06695*
Y00895*
X06699*
Y00895*
X06803*
Y00894*
X06805*
Y00894*
X06808*
Y00893*
X06809*
Y00893*
X06811*
Y00892*
X06813*
Y00892*
X06814*
Y00891*
X06815*
Y0089*
X06816*
Y0089*
X06817*
Y00889*
X06817*
Y00889*
X06818*
Y00888*
X06819*
Y00888*
X0682*
Y00887*
X06821*
Y00887*
X06821*
Y00886*
X06822*
Y00886*
X06822*
Y00885*
X06823*
Y00885*
X06823*
Y00884*
X06824*
Y00883*
X06824*
Y00883*
X06825*
Y00882*
X06825*
Y00882*
X06826*
Y00881*
X06827*
Y00881*
Y0088*
X06827*
Y0088*
X06828*
Y00879*
X06828*
Y00879*
Y00878*
X06829*
Y00877*
Y00877*
X06829*
Y00876*
X0683*
Y00876*
Y00875*
X0683*
Y00875*
Y00874*
X06831*
Y00874*
Y00873*
Y00873*
X06831*
Y00872*
Y00872*
X06832*
Y00871*
Y0087*
Y0087*
X06833*
Y00869*
Y00869*
Y00868*
Y00868*
X06833*
Y00867*
Y00867*
Y00866*
Y00866*
Y00865*
X06834*
Y00865*
Y00864*
Y00863*
Y00863*
Y00862*
Y00862*
Y00861*
Y00861*
Y0086*
Y0086*
Y00859*
Y00859*
Y00858*
Y00857*
Y00857*
Y00856*
Y00856*
Y00855*
Y00855*
Y00854*
Y00854*
X06833*
Y00853*
Y00853*
Y00852*
Y00852*
Y00851*
X06833*
Y0085*
Y0085*
Y00849*
X06832*
Y00849*
Y00848*
Y00848*
X06831*
Y00847*
Y00847*
Y00846*
X06831*
Y00846*
Y00845*
X0683*
Y00845*
Y00844*
X0683*
Y00843*
Y00843*
X06829*
Y00842*
Y00842*
X06829*
Y00841*
Y00841*
X06828*
Y0084*
X06828*
Y0084*
Y00839*
X06827*
Y00839*
X06827*
Y00838*
X06826*
Y00837*
X06825*
Y00837*
Y00836*
X06825*
Y00836*
X06824*
Y00835*
X06824*
Y00835*
X06823*
Y00834*
X06823*
Y00834*
X06822*
Y00833*
X06822*
Y00833*
X06821*
Y00832*
X0682*
Y00832*
X0682*
Y00831*
X06818*
Y0083*
X06818*
Y0083*
X06817*
Y00829*
X06816*
Y00829*
X06815*
Y00828*
X06814*
Y00828*
X06813*
Y00827*
X06812*
Y00827*
X0681*
Y00826*
X06809*
Y00826*
X06807*
Y00825*
X06804*
Y00825*
X06801*
Y00824*
X068*
Y00825*
X06799*
Y00824*
X06637*
Y00825*
X06636*
Y00824*
X06631*
Y00823*
X06628*
Y00823*
X06626*
Y00822*
X06624*
Y00822*
X06623*
Y00821*
X06622*
Y00821*
X06621*
Y0082*
X0662*
Y0082*
X06619*
Y00819*
X06618*
Y00819*
X06617*
Y00818*
X06616*
Y00817*
X06615*
Y00817*
X06615*
Y00816*
X06614*
Y00816*
X06614*
Y00815*
X06612*
Y00815*
X06612*
Y00814*
X06611*
Y00814*
X06611*
Y00813*
X0661*
Y00813*
X0661*
Y00812*
Y00812*
X06609*
Y00811*
X06609*
Y0081*
X06608*
Y0081*
X06608*
Y00809*
Y00809*
X06607*
Y00808*
X06607*
Y00808*
Y00807*
X06606*
Y00807*
X06605*
Y00806*
Y00806*
X06605*
Y00805*
Y00805*
X06604*
Y00804*
Y00803*
X06604*
Y00803*
Y00802*
X06603*
Y00802*
Y00801*
Y00801*
X06603*
Y008*
Y008*
Y00799*
X06602*
Y00799*
Y00798*
Y00797*
X06602*
Y00797*
Y00796*
Y00796*
Y00795*
Y00795*
X06601*
Y00794*
Y00794*
Y00793*
Y00793*
Y00792*
Y00792*
Y00791*
Y0079*
Y0079*
Y00789*
Y00789*
Y00788*
Y00788*
Y00787*
Y00787*
Y00786*
Y00786*
Y00785*
Y00785*
Y00784*
Y00783*
X06602*
Y00783*
Y00782*
Y00782*
Y00781*
Y00781*
X06602*
Y0078*
Y0078*
Y00779*
X06603*
Y00779*
Y00778*
Y00777*
X06603*
Y00777*
Y00776*
Y00776*
X06604*
Y00775*
Y00775*
X06604*
Y00774*
Y00774*
X06605*
Y00773*
Y00773*
X06605*
Y00772*
Y00772*
X06606*
Y00771*
Y0077*
X06607*
Y0077*
X06607*
Y00769*
Y00769*
X06608*
Y00768*
X06608*
Y00768*
X06609*
Y00767*
Y00767*
X06609*
Y00766*
X0661*
Y00766*
X0661*
Y00765*
X06611*
Y00765*
X06611*
Y00764*
X06612*
Y00763*
X06612*
Y00763*
X06613*
Y00762*
X06614*
Y00762*
X06615*
Y00761*
X06615*
Y00761*
X06616*
Y0076*
X06617*
Y0076*
X06617*
Y00759*
X06618*
Y00759*
X0662*
Y00758*
X06621*
Y00757*
X06622*
Y00757*
X06623*
Y00756*
X06624*
Y00756*
X06625*
Y00755*
X06628*
Y00755*
X0663*
Y00754*
X06635*
Y00754*
X06747*
Y00753*
X0675*
Y00753*
X06751*
Y00752*
X06753*
Y00752*
X06755*
Y00751*
X06756*
Y0075*
X06757*
Y0075*
X06758*
Y00749*
X06759*
Y00749*
X0676*
Y00748*
X06761*
Y00748*
X06762*
Y00747*
X06763*
Y00747*
X06763*
Y00746*
X06764*
Y00746*
X06764*
Y00745*
X06765*
Y00745*
X06766*
Y00744*
X06767*
Y00743*
X06767*
Y00743*
X06768*
Y00742*
X06768*
Y00742*
Y00741*
X06769*
Y00741*
X06769*
Y0074*
X0677*
Y0074*
X0677*
Y00739*
Y00739*
X06771*
Y00738*
X06771*
Y00737*
Y00737*
X06772*
Y00736*
X06772*
Y00736*
Y00735*
X06773*
Y00735*
Y00734*
X06774*
Y00734*
Y00733*
X06774*
Y00733*
Y00732*
X06775*
Y00732*
Y00731*
Y0073*
X06775*
Y0073*
Y00729*
Y00729*
X06776*
Y00728*
Y00728*
Y00727*
X06776*
Y00727*
Y00726*
Y00726*
Y00725*
Y00725*
Y00724*
X06777*
Y00723*
Y00723*
Y00722*
Y00722*
Y00721*
Y00721*
Y0072*
Y0072*
Y00719*
X06777*
Y00719*
Y00718*
X06777*
Y00717*
Y00717*
Y00716*
Y00716*
Y00715*
Y00715*
Y00714*
Y00714*
Y00713*
Y00713*
X06776*
Y00712*
Y00712*
Y00711*
Y0071*
Y0071*
X06776*
Y00709*
Y00709*
Y00708*
X06775*
Y00708*
Y00707*
Y00707*
X06775*
Y00706*
Y00706*
Y00705*
X06774*
Y00704*
Y00704*
Y00703*
X06774*
Y00703*
Y00702*
X06773*
Y00702*
Y00701*
X06772*
Y00701*
Y007*
X06772*
Y007*
X06771*
Y00699*
Y00699*
X06771*
Y00698*
X0677*
Y00697*
Y00697*
X0677*
Y00696*
X06769*
Y00696*
X06769*
Y00695*
Y00695*
X06768*
Y00694*
X06768*
Y00694*
X06767*
Y00693*
X06767*
Y00693*
X06766*
Y00692*
X06765*
Y00692*
X06765*
Y00691*
X06764*
Y0069*
X06764*
Y0069*
X06763*
Y00689*
X06762*
Y00689*
X06762*
Y00688*
X06761*
Y00688*
X0676*
Y00687*
X0676*
Y00687*
X06758*
Y00686*
X06757*
Y00686*
X06756*
Y00685*
X06755*
Y00684*
X06754*
Y00684*
X06751*
Y00683*
X06362*
Y00683*
X06361*
Y00682*
X06361*
Y00682*
X0636*
Y00681*
X06359*
Y00681*
Y0068*
X06359*
Y0068*
Y00679*
Y00679*
Y00678*
Y00677*
Y00677*
Y00676*
Y00676*
Y00675*
Y00675*
Y00674*
Y00674*
Y00673*
Y00673*
Y00672*
Y00672*
Y00671*
Y0067*
Y0067*
Y00669*
Y00669*
Y00668*
Y00668*
Y00667*
Y00667*
Y00666*
Y00666*
Y00665*
Y00664*
Y00664*
Y00663*
Y00663*
Y00662*
Y00662*
Y00661*
Y00661*
Y0066*
Y0066*
Y00659*
Y00659*
Y00658*
Y00657*
Y00657*
Y00656*
Y00656*
Y00655*
Y00655*
Y00654*
Y00654*
Y00653*
Y00653*
Y00652*
Y00652*
Y00651*
Y0065*
Y0065*
Y00649*
Y00649*
Y00648*
Y00648*
Y00647*
Y00647*
Y00646*
Y00646*
Y00645*
Y00644*
Y00644*
Y00643*
Y00643*
Y00642*
Y00642*
Y00641*
Y00641*
Y0064*
Y0064*
Y00639*
Y00639*
Y00638*
Y00637*
Y00637*
Y00636*
Y00636*
Y00635*
Y00635*
Y00634*
Y00634*
Y00633*
Y00633*
Y00632*
Y00632*
Y00631*
Y0063*
Y0063*
Y00629*
Y00629*
Y00628*
Y00628*
Y00627*
Y00627*
X06358*
Y00626*
Y00626*
X06358*
Y00625*
Y00624*
X06357*
Y00624*
X06356*
Y00623*
X06355*
Y00623*
X06252*
Y00623*
X0625*
Y00624*
X0625*
Y00624*
X06249*
Y00625*
X06249*
Y00626*
Y00626*
X06248*
Y00627*
Y00627*
Y00628*
Y00628*
Y00629*
Y00629*
Y0063*
Y0063*
Y00631*
Y00632*
Y00632*
Y00633*
Y00633*
Y00634*
Y00634*
Y00635*
Y00635*
Y00636*
Y00636*
Y00637*
Y00637*
Y00638*
Y00639*
Y00639*
Y0064*
Y0064*
Y00641*
Y00641*
Y00642*
Y00642*
Y00643*
Y00643*
Y00644*
Y00644*
Y00645*
Y00646*
Y00646*
Y00647*
Y00647*
Y00648*
Y00648*
Y00649*
Y00649*
Y0065*
Y0065*
Y00651*
Y00652*
Y00652*
Y00653*
Y00653*
Y00654*
Y00654*
Y00655*
Y00655*
Y00656*
Y00656*
Y00657*
Y00657*
Y00658*
Y00659*
Y00659*
X06248*
Y0066*
Y0066*
Y00661*
X06247*
Y00661*
Y00662*
X06246*
Y00662*
X06245*
Y00663*
X06244*
Y00663*
X06242*
Y00663*
X06241*
Y00662*
X0624*
Y00662*
X06239*
Y00661*
X06239*
Y00661*
X06238*
Y0066*
Y0066*
Y00659*
Y00659*
X06238*
Y00658*
Y00657*
Y00657*
Y00656*
Y00656*
Y00655*
Y00655*
Y00654*
Y00654*
Y00653*
Y00653*
Y00652*
Y00652*
Y00651*
Y0065*
Y0065*
Y00649*
Y00649*
Y00648*
Y00648*
Y00647*
Y00647*
Y00646*
Y00646*
Y00645*
Y00644*
Y00644*
Y00643*
Y00643*
Y00642*
Y00642*
Y00641*
Y00641*
Y0064*
Y0064*
Y00639*
Y00639*
Y00638*
Y00637*
Y00637*
Y00636*
Y00636*
Y00635*
Y00635*
Y00634*
Y00634*
Y00633*
Y00633*
Y00632*
Y00632*
Y00631*
Y0063*
Y0063*
Y00629*
Y00629*
Y00628*
Y00628*
Y00627*
Y00627*
Y00626*
Y00626*
X06237*
Y00625*
X06237*
Y00624*
X06236*
Y00624*
X06236*
Y00623*
X06234*
Y00623*
X06181*
Y00623*
X0618*
Y00624*
X06179*
Y00624*
X06178*
Y00625*
Y00626*
X06178*
Y00626*
Y00627*
Y00627*
X06177*
Y00628*
Y00628*
Y00629*
Y00629*
Y0063*
Y0063*
Y00631*
Y00632*
Y00632*
Y00633*
Y00633*
Y00634*
Y00634*
Y00635*
Y00635*
Y00636*
Y00636*
Y00637*
Y00637*
Y00638*
Y00639*
Y00639*
Y0064*
Y0064*
Y00641*
Y00641*
Y00642*
Y00642*
Y00643*
Y00643*
Y00644*
Y00644*
Y00645*
Y00646*
Y00646*
Y00647*
Y00647*
Y00648*
Y00648*
Y00649*
Y00649*
Y0065*
Y0065*
Y00651*
Y00652*
Y00652*
Y00653*
Y00653*
Y00654*
Y00654*
Y00655*
Y00655*
Y00656*
Y00656*
Y00657*
Y00657*
Y00658*
Y00659*
Y00659*
Y0066*
Y0066*
Y00661*
Y00661*
Y00662*
Y00662*
Y00663*
Y00663*
Y00664*
Y00664*
Y00665*
Y00666*
Y00666*
Y00667*
Y00667*
Y00668*
Y00668*
Y00669*
Y00669*
Y0067*
Y0067*
Y00671*
X06178*
Y00672*
X06177*
Y00672*
Y00673*
Y00673*
Y00674*
Y00674*
Y00675*
Y00675*
Y00676*
Y00676*
X06177*
Y00677*
Y00677*
X06176*
Y00678*
Y00679*
X06176*
Y00679*
Y0068*
X06175*
Y0068*
X06175*
Y00681*
X06174*
Y00681*
X06173*
Y00682*
X06172*
Y00682*
X06171*
Y00683*
X0617*
Y00683*
X06165*
Y00683*
X06164*
Y00682*
X06163*
Y00682*
X06162*
Y00681*
X06161*
Y00681*
X06161*
Y0068*
X0616*
Y0068*
X06159*
Y00679*
X06159*
Y00679*
Y00678*
X06158*
Y00677*
Y00677*
X06158*
Y00676*
Y00676*
Y00675*
Y00675*
Y00674*
Y00674*
X06157*
Y00673*
X06158*
Y00673*
Y00672*
X06157*
Y00672*
X06158*
Y00671*
Y0067*
Y0067*
Y00669*
Y00669*
Y00668*
Y00668*
Y00667*
Y00667*
Y00666*
Y00666*
Y00665*
Y00664*
Y00664*
Y00663*
Y00663*
Y00662*
Y00662*
Y00661*
Y00661*
Y0066*
Y0066*
Y00659*
Y00659*
Y00658*
Y00657*
Y00657*
Y00656*
Y00656*
Y00655*
Y00655*
Y00654*
Y00654*
Y00653*
Y00653*
Y00652*
Y00652*
Y00651*
Y0065*
Y0065*
Y00649*
Y00649*
Y00648*
X06157*
Y00648*
Y00647*
Y00647*
Y00646*
X06157*
Y00646*
X06156*
Y00645*
X06156*
Y00644*
X06155*
Y00644*
X06153*
Y00643*
X06121*
Y00644*
X06119*
Y00644*
X06119*
Y00645*
X06118*
Y00646*
X06118*
Y00646*
X06117*
Y00647*
Y00647*
Y00648*
X06117*
Y00648*
Y00649*
Y00649*
Y0065*
Y0065*
Y00651*
Y00652*
Y00652*
Y00653*
Y00653*
Y00654*
Y00654*
Y00655*
Y00655*
Y00656*
Y00656*
Y00657*
Y00657*
Y00658*
Y00659*
Y00659*
Y0066*
Y0066*
Y00661*
Y00661*
Y00662*
Y00662*
Y00663*
Y00663*
Y00664*
Y00664*
Y00665*
Y00666*
Y00666*
Y00667*
Y00667*
Y00668*
Y00668*
Y00669*
Y00669*
Y0067*
Y0067*
Y00671*
Y00672*
Y00672*
Y00673*
Y00673*
Y00674*
Y00674*
Y00675*
Y00675*
X06117*
Y00676*
Y00676*
X06117*
Y00677*
X06117*
Y00677*
X06117*
Y00678*
Y00679*
Y00679*
Y0068*
Y0068*
Y00681*
X06116*
Y00681*
Y00682*
X06116*
Y00682*
X06115*
Y00683*
X06113*
Y00683*
X0603*
Y00683*
X06029*
Y00682*
X06028*
Y00682*
X06028*
Y00681*
X06027*
Y00681*
Y0068*
X06026*
Y0068*
Y00679*
Y00679*
Y00678*
Y00677*
Y00677*
Y00676*
Y00676*
Y00675*
Y00675*
Y00674*
Y00674*
Y00673*
Y00673*
Y00672*
Y00672*
Y00671*
Y0067*
Y0067*
Y00669*
Y00669*
Y00668*
Y00668*
Y00667*
Y00667*
Y00666*
Y00666*
Y00665*
Y00664*
Y00664*
Y00663*
Y00663*
Y00662*
Y00662*
Y00661*
Y00661*
Y0066*
Y0066*
Y00659*
Y00659*
Y00658*
Y00657*
Y00657*
Y00656*
Y00656*
Y00655*
Y00655*
Y00654*
Y00654*
Y00653*
Y00653*
Y00652*
Y00652*
Y00651*
Y0065*
Y0065*
Y00649*
Y00649*
Y00648*
Y00648*
Y00647*
Y00647*
Y00646*
Y00646*
Y00645*
Y00644*
Y00644*
Y00643*
Y00643*
Y00642*
Y00642*
Y00641*
Y00641*
Y0064*
Y0064*
Y00639*
Y00639*
Y00638*
Y00637*
Y00637*
Y00636*
Y00636*
Y00635*
Y00635*
Y00634*
Y00634*
Y00633*
X05946*
Y00634*
Y00634*
Y00635*
Y00635*
Y00636*
Y00636*
Y00637*
Y00637*
Y00638*
Y00639*
Y00639*
Y0064*
Y0064*
Y00641*
Y00641*
Y00642*
Y00642*
Y00643*
Y00643*
Y00644*
Y00644*
Y00645*
Y00646*
Y00646*
Y00647*
Y00647*
Y00648*
Y00648*
Y00649*
Y00649*
Y0065*
Y0065*
Y00651*
Y00652*
Y00652*
Y00653*
Y00653*
Y00654*
Y00654*
Y00655*
Y00655*
Y00656*
Y00656*
Y00657*
Y00657*
Y00658*
Y00659*
Y00659*
Y0066*
Y0066*
Y00661*
Y00661*
Y00662*
Y00662*
Y00663*
Y00663*
Y00664*
Y00664*
Y00665*
Y00666*
Y00666*
Y00667*
Y00667*
Y00668*
Y00668*
Y00669*
Y00669*
Y0067*
Y0067*
Y00671*
Y00672*
Y00672*
Y00673*
Y00673*
Y00674*
Y00674*
Y00675*
Y00675*
Y00676*
Y00676*
Y00677*
Y00677*
Y00678*
Y00679*
Y00679*
Y0068*
Y0068*
Y00681*
Y00681*
Y00682*
X05998*
Y00682*
Y00683*
Y00683*
Y00684*
Y00684*
Y00685*
Y00686*
Y00686*
Y00687*
Y00687*
Y00688*
Y00688*
Y00689*
Y00689*
Y0069*
Y0069*
Y00691*
Y00692*
Y00692*
Y00693*
Y00693*
Y00694*
Y00694*
Y00695*
Y00695*
Y00696*
Y00696*
Y00697*
Y00697*
Y00698*
Y00699*
Y00699*
Y007*
Y007*
Y00701*
Y00701*
Y00702*
Y00702*
Y00703*
Y00703*
Y00704*
Y00704*
Y00705*
Y00706*
Y00706*
Y00707*
Y00707*
Y00708*
Y00708*
Y00709*
Y00709*
Y0071*
Y0071*
Y00711*
Y00712*
Y00712*
Y00713*
Y00713*
Y00714*
Y00714*
Y00715*
Y00715*
Y00716*
Y00716*
Y00717*
Y00717*
Y00718*
Y00719*
Y00719*
Y0072*
Y0072*
Y00721*
Y00721*
Y00722*
Y00722*
Y00723*
Y00723*
Y00724*
Y00725*
Y00725*
Y00726*
Y00726*
Y00727*
Y00727*
Y00728*
Y00728*
Y00729*
Y00729*
Y0073*
Y0073*
Y00731*
Y00732*
Y00732*
Y00733*
Y00733*
Y00734*
Y00734*
Y00735*
Y00735*
Y00736*
Y00736*
Y00737*
Y00737*
Y00738*
Y00739*
Y00739*
Y0074*
Y0074*
Y00741*
Y00741*
X05946*
Y00742*
Y00742*
Y00743*
Y00743*
Y00744*
Y00745*
Y00745*
Y00746*
Y00746*
Y00747*
Y00747*
Y00748*
Y00748*
Y00749*
Y00749*
Y0075*
Y0075*
Y00751*
Y00752*
Y00752*
Y00753*
Y00753*
Y00754*
Y00754*
Y00755*
X05998*
Y00755*
Y00756*
Y00756*
Y00757*
Y00757*
Y00758*
Y00759*
Y00759*
Y0076*
Y0076*
Y00761*
Y00761*
Y00762*
Y00762*
Y00763*
Y00763*
Y00764*
Y00765*
Y00765*
Y00766*
Y00766*
Y00767*
Y00767*
Y00768*
Y00768*
Y00769*
Y00769*
Y0077*
Y0077*
Y00771*
Y00772*
Y00772*
Y00773*
Y00773*
Y00774*
Y00774*
Y00775*
Y00775*
Y00776*
Y00776*
Y00777*
Y00777*
Y00778*
Y00779*
Y00779*
Y0078*
Y0078*
Y00781*
Y00781*
Y00782*
Y00782*
Y00783*
Y00783*
Y00784*
Y00785*
Y00785*
Y00786*
Y00786*
Y00787*
Y00787*
Y00788*
Y00788*
Y00789*
Y00789*
Y0079*
Y0079*
Y00791*
Y00792*
Y00792*
Y00793*
Y00793*
Y00794*
Y00794*
Y00795*
Y00795*
Y00796*
Y00796*
Y00797*
Y00797*
Y00798*
Y00799*
Y00799*
Y008*
Y008*
Y00801*
Y00801*
Y00802*
Y00802*
Y00803*
Y00803*
Y00804*
Y00805*
Y00805*
Y00806*
Y00806*
Y00807*
Y00807*
Y00808*
Y00808*
Y00809*
Y00809*
Y0081*
Y0081*
Y00811*
Y00812*
Y00812*
Y00813*
Y00813*
Y00814*
Y00814*
X05946*
Y00815*
X05946*
Y00815*
Y00816*
Y00816*
Y00817*
Y00817*
Y00818*
Y00819*
Y00819*
Y0082*
Y0082*
Y00821*
Y00821*
Y00822*
Y00822*
Y00823*
Y00823*
Y00824*
Y00825*
Y00825*
Y00826*
Y00826*
Y00827*
Y00827*
Y00828*
X05998*
Y00828*
Y00829*
Y00829*
Y0083*
Y0083*
Y00831*
Y00832*
Y00832*
Y00833*
Y00833*
Y00834*
Y00834*
Y00835*
Y00835*
Y00836*
Y00836*
Y00837*
Y00837*
Y00838*
Y00839*
Y00839*
Y0084*
Y0084*
Y00841*
Y00841*
Y00842*
Y00842*
Y00843*
Y00843*
Y00844*
Y00845*
Y00845*
Y00846*
Y00846*
Y00847*
Y00847*
Y00848*
Y00848*
Y00849*
Y00849*
Y0085*
Y0085*
Y00851*
Y00852*
Y00852*
Y00853*
Y00853*
Y00854*
Y00854*
Y00855*
Y00855*
Y00856*
Y00856*
Y00857*
Y00857*
Y00858*
Y00859*
Y00859*
Y0086*
Y0086*
Y00861*
Y00861*
Y00862*
Y00862*
Y00863*
Y00863*
Y00864*
Y00865*
Y00865*
Y00866*
Y00866*
Y00867*
Y00867*
Y00868*
Y00868*
Y00869*
Y00869*
Y0087*
Y0087*
Y00871*
Y00872*
Y00872*
Y00873*
Y00873*
Y00874*
Y00874*
Y00875*
Y00875*
Y00876*
Y00876*
Y00877*
Y00877*
Y00878*
Y00879*
Y00879*
Y0088*
Y0088*
Y00881*
Y00881*
Y00882*
Y00882*
Y00883*
Y00883*
Y00884*
Y00885*
Y00885*
Y00886*
Y00886*
Y00887*
Y00887*
Y00888*
X05946*
Y00888*
Y00889*
Y00889*
Y0089*
Y0089*
Y00891*
Y00892*
Y00892*
Y00893*
Y00893*
Y00894*
Y00894*
Y00895*
Y00895*
Y00896*
Y00896*
Y00897*
Y00897*
Y00898*
Y00899*
Y00899*
Y009*
Y009*
Y00901*
X05946*
Y00901*
X05998*
Y00902*
Y00902*
Y00903*
Y00903*
Y00904*
Y00905*
Y00905*
Y00906*
Y00906*
Y00907*
Y00907*
Y00908*
Y00908*
Y00909*
Y00909*
Y0091*
Y0091*
Y00911*
Y00912*
Y00912*
Y00913*
Y00913*
Y00914*
Y00914*
Y00915*
Y00915*
Y00916*
Y00916*
Y00917*
Y00918*
Y00918*
Y00919*
Y00919*
Y0092*
Y0092*
Y00921*
Y00921*
Y00922*
Y00922*
Y00923*
Y00923*
Y00924*
Y00925*
Y00925*
Y00926*
Y00926*
Y00927*
Y00927*
Y00928*
Y00928*
Y00929*
Y00929*
Y0093*
Y0093*
Y00931*
Y00932*
Y00932*
Y00933*
Y00933*
Y00934*
Y00934*
Y00935*
Y00935*
Y00936*
Y00936*
Y00937*
Y00938*
Y00938*
Y00939*
Y00939*
Y0094*
Y0094*
Y00941*
Y00941*
Y00942*
Y00942*
Y00943*
Y00943*
Y00944*
Y00945*
Y00945*
Y00946*
Y00946*
Y00947*
Y00947*
Y00948*
Y00948*
Y00949*
Y00949*
Y0095*
Y0095*
Y00951*
Y00952*
Y00952*
Y00953*
Y00953*
Y00954*
Y00954*
Y00955*
Y00955*
Y00956*
Y00956*
Y00957*
Y00958*
Y00958*
Y00959*
Y00959*
Y0096*
Y0096*
Y00961*
X05946*
Y00961*
Y00962*
Y00962*
Y00963*
Y00963*
Y00964*
Y00965*
Y00965*
Y00966*
Y00966*
Y00967*
Y00967*
Y00968*
Y00968*
Y00969*
Y00969*
Y0097*
Y0097*
Y00971*
Y00972*
Y00972*
Y00973*
Y00973*
Y00974*
Y00974*
Y00975*
Y00975*
Y00976*
Y00976*
Y00977*
Y00978*
Y00978*
Y00979*
Y00979*
Y0098*
Y0098*
Y00981*
Y00981*
Y00982*
Y00982*
Y00983*
Y00983*
Y00984*
Y00985*
Y00985*
Y00986*
Y00986*
Y00987*
Y00987*
Y00988*
Y00988*
Y00989*
Y00989*
Y0099*
Y0099*
Y00991*
Y00992*
Y00992*
Y00993*
Y00993*
Y00994*
Y00994*
Y00995*
Y00995*
Y00996*
Y00996*
Y00997*
Y00998*
Y00998*
Y00999*
Y00999*
Y01*
Y01*
Y01001*
Y01001*
Y01002*
Y01002*
Y01003*
Y01003*
Y01004*
Y01005*
Y01005*
Y01006*
Y01006*
Y01007*
Y01007*
Y01008*
Y01008*
Y01009*
Y01009*
Y0101*
Y0101*
Y01011*
Y01012*
Y01012*
Y01013*
Y01013*
Y01014*
Y01014*
Y01015*
Y01015*
Y01016*
Y01016*
Y01017*
Y01018*
Y01018*
Y01019*
Y01019*
Y0102*
Y0102*
Y01021*
Y01021*
Y01022*
Y01022*
Y01023*
Y01023*
Y01024*
Y01025*
Y01025*
Y01026*
Y01026*
Y01027*
Y01027*
Y01028*
Y01028*
Y01029*
Y01029*
Y0103*
Y0103*
Y01031*
Y01032*
Y01032*
Y01033*
Y01033*
Y01034*
Y01034*
Y01035*
Y01035*
Y01036*
Y01036*
Y01037*
Y01038*
Y01038*
Y01039*
Y01039*
Y0104*
Y0104*
Y01041*
Y01041*
Y01042*
Y01042*
Y01043*
Y01043*
Y01044*
Y01045*
Y01045*
Y01046*
Y01046*
Y01047*
Y01047*
Y01048*
Y01048*
Y01049*
Y01049*
Y0105*
Y0105*
Y01051*
Y01052*
Y01052*
Y01053*
Y01053*
Y01054*
Y01054*
Y01055*
Y01055*
Y01056*
Y01056*
Y01057*
Y01058*
Y01058*
Y01059*
Y01059*
Y0106*
Y0106*
Y01061*
Y01061*
Y01062*
Y01062*
Y01063*
Y01063*
Y01064*
Y01065*
Y01065*
Y01066*
Y01066*
Y01067*
Y01067*
Y01068*
Y01068*
Y01069*
Y01069*
Y0107*
Y0107*
Y01071*
Y01072*
Y01072*
Y01073*
Y01073*
Y01074*
Y01074*
Y01075*
Y01075*
Y01076*
Y01076*
Y01077*
Y01078*
Y01078*
Y01079*
Y01079*
Y0108*
Y0108*
Y01081*
Y01081*
Y01082*
Y01082*
Y01083*
Y01083*
Y01084*
Y01085*
Y01085*
Y01086*
Y01086*
Y01087*
Y01087*
Y01088*
Y01088*
Y01089*
Y01089*
Y0109*
Y01091*
Y01091*
Y01092*
Y01092*
Y01093*
Y01093*
Y01094*
Y01094*
Y01095*
Y01095*
Y01096*
Y01096*
Y01097*
Y01098*
Y01098*
Y01099*
Y01099*
Y011*
Y011*
Y01101*
Y01101*
Y01102*
Y01102*
Y01103*
Y01103*
Y01104*
Y01105*
Y01105*
Y01106*
Y01106*
Y01107*
Y01107*
Y01108*
Y01108*
Y01109*
Y01109*
Y0111*
Y01111*
Y01111*
Y01112*
Y01112*
Y01113*
Y01113*
Y01114*
Y01114*
Y01115*
Y01115*
Y01116*
Y01116*
Y01117*
Y01118*
Y01118*
Y01119*
Y01119*
Y0112*
Y0112*
Y01121*
Y01121*
Y01122*
Y01122*
Y01123*
Y01123*
Y01124*
Y01125*
Y01125*
Y01126*
Y01126*
Y01127*
Y01127*
Y01128*
Y01128*
Y01129*
Y01129*
Y0113*
Y01131*
Y01131*
Y01132*
Y01132*
Y01133*
Y01133*
Y01134*
Y01134*
Y01135*
Y01135*
Y01136*
Y01136*
Y01137*
Y01138*
Y01138*
Y01139*
Y01139*
Y0114*
Y0114*
Y01141*
Y01141*
Y01142*
Y01142*
Y01143*
Y01143*
Y01144*
Y01145*
Y01145*
Y01146*
Y01146*
Y01147*
Y01147*
Y01148*
Y01148*
Y01149*
Y01149*
Y0115*
Y01151*
Y01151*
Y01152*
Y01152*
Y01153*
Y01153*
Y01154*
Y01154*
Y01155*
Y01155*
Y01156*
Y01156*
Y01157*
Y01158*
Y01158*
Y01159*
Y01159*
Y0116*
Y0116*
Y01161*
Y01161*
Y01162*
Y01162*
Y01163*
Y01163*
Y01164*
Y01165*
Y01165*
Y01166*
Y01166*
Y01167*
Y01167*
Y01168*
Y01168*
Y01169*
Y01169*
Y0117*
Y01171*
Y01171*
Y01172*
Y01172*
Y01173*
Y01173*
Y01174*
Y01174*
Y01175*
Y01175*
Y01176*
Y01176*
X05946*
Y01177*
X06629*
Y01176*
G37*
G36*
X05971Y00805D02*
X05973D01*
Y00804*
X05975*
Y00803*
X05977*
Y00803*
X05978*
Y00802*
X05979*
Y00802*
X05979*
Y00801*
X0598*
Y00801*
X05981*
Y008*
X05982*
Y008*
X05982*
Y00799*
X05983*
Y00799*
X05983*
Y00798*
X05984*
Y00797*
X05984*
Y00797*
X05985*
Y00796*
Y00796*
X05985*
Y00795*
X05986*
Y00795*
Y00794*
X05986*
Y00794*
Y00793*
X05987*
Y00793*
Y00792*
X05988*
Y00792*
Y00791*
Y0079*
X05988*
Y0079*
Y00789*
Y00789*
Y00788*
X05989*
Y00788*
Y00787*
Y00787*
Y00786*
Y00786*
Y00785*
Y00785*
Y00784*
Y00783*
Y00783*
Y00782*
Y00782*
Y00781*
X05988*
Y00781*
Y0078*
Y0078*
Y00779*
X05988*
Y00779*
Y00778*
Y00777*
X05987*
Y00777*
Y00776*
Y00776*
X05986*
Y00775*
Y00775*
X05986*
Y00774*
X05985*
Y00774*
Y00773*
X05985*
Y00773*
X05984*
Y00772*
Y00772*
X05984*
Y00771*
X05983*
Y0077*
X05983*
Y0077*
X05982*
Y00769*
X05982*
Y00769*
X0598*
Y00768*
X0598*
Y00768*
X05979*
Y00767*
X05978*
Y00767*
X05977*
Y00766*
X05976*
Y00766*
X05975*
Y00765*
X05972*
Y00765*
X05964*
Y00765*
X05963*
Y00766*
X05961*
Y00766*
X05959*
Y00767*
X05959*
Y00767*
X05958*
Y00768*
X05957*
Y00768*
X05956*
Y00769*
X05956*
Y00769*
X05955*
Y0077*
X05954*
Y0077*
X05953*
Y00771*
X05953*
Y00772*
Y00772*
X05952*
Y00773*
X05952*
Y00773*
X05951*
Y00774*
Y00774*
X05951*
Y00775*
Y00775*
X0595*
Y00776*
Y00776*
X0595*
Y00777*
Y00777*
X05949*
Y00778*
Y00779*
Y00779*
X05949*
Y0078*
Y0078*
Y00781*
Y00781*
Y00782*
X05948*
Y00782*
Y00783*
Y00783*
Y00784*
Y00785*
Y00785*
Y00786*
Y00786*
Y00787*
Y00787*
X05949*
Y00788*
Y00788*
Y00789*
Y00789*
Y0079*
X05949*
Y0079*
Y00791*
Y00792*
X0595*
Y00792*
Y00793*
Y00793*
X0595*
Y00794*
Y00794*
X05951*
Y00795*
Y00795*
X05951*
Y00796*
X05952*
Y00796*
Y00797*
X05952*
Y00797*
X05953*
Y00798*
X05953*
Y00799*
X05954*
Y00799*
X05955*
Y008*
X05955*
Y008*
X05956*
Y00801*
X05956*
Y00801*
X05957*
Y00802*
X05958*
Y00802*
X05959*
Y00803*
X0596*
Y00803*
X05962*
Y00804*
X05963*
Y00805*
X05966*
Y00805*
X05971*
Y00805*
G37*
G36*
X05973Y00731D02*
X05975D01*
Y0073*
X05976*
Y0073*
X05977*
Y00729*
X05978*
Y00729*
X05979*
Y00728*
X0598*
Y00728*
X05981*
Y00727*
X05982*
Y00727*
X05982*
Y00726*
X05983*
Y00726*
X05983*
Y00725*
X05984*
Y00725*
X05984*
Y00724*
X05985*
Y00723*
Y00723*
X05985*
Y00722*
X05986*
Y00722*
Y00721*
X05986*
Y00721*
Y0072*
X05987*
Y0072*
Y00719*
X05988*
Y00719*
Y00718*
Y00717*
X05988*
Y00717*
Y00716*
Y00716*
Y00715*
Y00715*
X05989*
Y00714*
Y00714*
Y00713*
Y00713*
Y00712*
Y00712*
Y00711*
Y0071*
Y0071*
Y00709*
Y00709*
Y00708*
X05988*
Y00708*
Y00707*
Y00707*
Y00706*
Y00706*
X05988*
Y00705*
Y00704*
Y00704*
X05987*
Y00703*
Y00703*
X05986*
Y00702*
Y00702*
X05986*
Y00701*
Y00701*
X05985*
Y007*
X05985*
Y007*
Y00699*
X05984*
Y00699*
X05984*
Y00698*
X05983*
Y00697*
X05983*
Y00697*
X05982*
Y00696*
X05982*
Y00696*
X05981*
Y00695*
X0598*
Y00695*
X05979*
Y00694*
X05978*
Y00694*
X05977*
Y00693*
X05976*
Y00693*
X05975*
Y00692*
X05973*
Y00692*
X05964*
Y00692*
X05962*
Y00693*
X0596*
Y00693*
X05959*
Y00694*
X05958*
Y00694*
X05957*
Y00695*
X05957*
Y00695*
X05956*
Y00696*
X05955*
Y00696*
X05955*
Y00697*
X05954*
Y00697*
X05953*
Y00698*
X05953*
Y00699*
X05952*
Y00699*
Y007*
X05952*
Y007*
X05951*
Y00701*
Y00701*
X05951*
Y00702*
Y00702*
X0595*
Y00703*
Y00703*
X0595*
Y00704*
Y00704*
X05949*
Y00705*
Y00706*
Y00706*
X05949*
Y00707*
Y00707*
Y00708*
Y00708*
Y00709*
X05948*
Y00709*
Y0071*
Y0071*
Y00711*
Y00712*
Y00712*
Y00713*
Y00713*
Y00714*
Y00714*
X05949*
Y00715*
Y00715*
Y00716*
Y00716*
Y00717*
X05949*
Y00717*
Y00718*
Y00719*
X0595*
Y00719*
Y0072*
X0595*
Y0072*
Y00721*
X05951*
Y00721*
Y00722*
X05951*
Y00722*
Y00723*
X05952*
Y00723*
X05952*
Y00724*
Y00725*
X05953*
Y00725*
X05953*
Y00726*
X05954*
Y00726*
X05955*
Y00727*
X05955*
Y00727*
X05956*
Y00728*
X05957*
Y00728*
X05957*
Y00729*
X05958*
Y00729*
X05959*
Y0073*
X0596*
Y0073*
X05962*
Y00731*
X05964*
Y00732*
X05973*
Y00731*
G37*
G36*
X05894Y01176D02*
X05899D01*
Y01176*
X05902*
Y01175*
X05904*
Y01175*
X05905*
Y01174*
X05906*
Y01174*
X05908*
Y01173*
X05909*
Y01173*
X0591*
Y01172*
X05911*
Y01172*
X05911*
Y01171*
X05912*
Y01171*
X05913*
Y0117*
X05913*
Y01169*
X05915*
Y01169*
X05915*
Y01168*
X05916*
Y01168*
X05916*
Y01167*
X05917*
Y01167*
X05917*
Y01166*
X05918*
Y01166*
X05918*
Y01165*
X05919*
Y01165*
Y01164*
X05919*
Y01163*
X0592*
Y01163*
X0592*
Y01162*
Y01162*
X05921*
Y01161*
X05922*
Y01161*
Y0116*
X05922*
Y0116*
Y01159*
X05923*
Y01159*
Y01158*
X05923*
Y01158*
Y01157*
X05924*
Y01156*
Y01156*
Y01155*
X05924*
Y01155*
Y01154*
X05925*
Y01154*
Y01153*
Y01153*
Y01152*
X05925*
Y01152*
Y01151*
Y01151*
Y0115*
Y01149*
X05926*
Y01149*
Y01148*
Y01148*
Y01147*
Y01147*
Y01146*
Y01146*
Y01145*
Y01145*
Y01144*
Y01143*
Y01143*
Y01142*
Y01142*
Y01141*
Y01141*
Y0114*
Y0114*
Y01139*
Y01139*
Y01138*
Y01138*
Y01137*
Y01136*
Y01136*
Y01135*
Y01135*
Y01134*
Y01134*
Y01133*
Y01133*
Y01132*
Y01132*
Y01131*
Y01131*
Y0113*
Y01129*
Y01129*
Y01128*
Y01128*
Y01127*
Y01127*
Y01126*
Y01126*
Y01125*
Y01125*
Y01124*
Y01123*
Y01123*
Y01122*
Y01122*
Y01121*
Y01121*
Y0112*
Y0112*
Y01119*
Y01119*
Y01118*
Y01118*
Y01117*
Y01116*
Y01116*
Y01115*
Y01115*
Y01114*
Y01114*
Y01113*
Y01113*
Y01112*
Y01112*
Y01111*
Y01111*
Y0111*
Y01109*
Y01109*
Y01108*
Y01108*
Y01107*
Y01107*
Y01106*
Y01106*
Y01105*
Y01105*
Y01104*
Y01103*
Y01103*
Y01102*
Y01102*
Y01101*
Y01101*
Y011*
Y011*
Y01099*
Y01099*
Y01098*
Y01098*
Y01097*
Y01096*
Y01096*
Y01095*
Y01095*
Y01094*
Y01094*
Y01093*
Y01093*
Y01092*
Y01092*
Y01091*
Y01091*
Y0109*
Y01089*
Y01089*
Y01088*
Y01088*
Y01087*
Y01087*
Y01086*
Y01086*
Y01085*
Y01085*
Y01084*
Y01083*
Y01083*
Y01082*
Y01082*
Y01081*
Y01081*
Y0108*
Y0108*
Y01079*
Y01079*
Y01078*
Y01078*
Y01077*
Y01076*
Y01076*
Y01075*
Y01075*
Y01074*
Y01074*
Y01073*
Y01073*
Y01072*
Y01072*
Y01071*
Y0107*
Y0107*
Y01069*
Y01069*
Y01068*
Y01068*
Y01067*
Y01067*
Y01066*
Y01066*
Y01065*
Y01065*
Y01064*
Y01063*
Y01063*
Y01062*
Y01062*
Y01061*
Y01061*
Y0106*
Y0106*
Y01059*
Y01059*
Y01058*
Y01058*
Y01057*
Y01056*
Y01056*
Y01055*
Y01055*
Y01054*
Y01054*
Y01053*
Y01053*
Y01052*
Y01052*
Y01051*
Y0105*
Y0105*
Y01049*
Y01049*
Y01048*
Y01048*
Y01047*
Y01047*
Y01046*
Y01046*
Y01045*
Y01045*
Y01044*
Y01043*
Y01043*
Y01042*
Y01042*
Y01041*
Y01041*
Y0104*
Y0104*
Y01039*
Y01039*
Y01038*
Y01038*
Y01037*
Y01036*
Y01036*
Y01035*
Y01035*
Y01034*
Y01034*
Y01033*
Y01033*
Y01032*
Y01032*
Y01031*
Y0103*
Y0103*
Y01029*
Y01029*
Y01028*
Y01028*
Y01027*
Y01027*
Y01026*
Y01026*
Y01025*
Y01025*
Y01024*
Y01023*
Y01023*
Y01022*
Y01022*
Y01021*
Y01021*
Y0102*
Y0102*
Y01019*
Y01019*
Y01018*
Y01018*
Y01017*
Y01016*
Y01016*
Y01015*
Y01015*
Y01014*
Y01014*
Y01013*
Y01013*
Y01012*
Y01012*
Y01011*
Y0101*
Y0101*
Y01009*
Y01009*
Y01008*
Y01008*
Y01007*
Y01007*
Y01006*
Y01006*
Y01005*
Y01005*
Y01004*
Y01003*
Y01003*
Y01002*
Y01002*
Y01001*
Y01001*
Y01*
Y01*
Y00999*
Y00999*
Y00998*
Y00998*
Y00997*
Y00996*
Y00996*
Y00995*
Y00995*
Y00994*
Y00994*
Y00993*
Y00993*
Y00992*
Y00992*
Y00991*
Y0099*
Y0099*
Y00989*
Y00989*
Y00988*
Y00988*
Y00987*
Y00987*
Y00986*
Y00986*
Y00985*
Y00985*
Y00984*
Y00983*
Y00983*
Y00982*
Y00982*
Y00981*
Y00981*
Y0098*
Y0098*
Y00979*
Y00979*
Y00978*
Y00978*
Y00977*
Y00976*
Y00976*
Y00975*
Y00975*
Y00974*
Y00974*
Y00973*
Y00973*
Y00972*
Y00972*
Y00971*
Y0097*
Y0097*
Y00969*
Y00969*
Y00968*
Y00968*
Y00967*
Y00967*
Y00966*
Y00966*
Y00965*
Y00965*
Y00964*
Y00963*
Y00963*
Y00962*
Y00962*
Y00961*
Y00961*
Y0096*
Y0096*
Y00959*
Y00959*
Y00958*
Y00958*
Y00957*
Y00956*
Y00956*
Y00955*
Y00955*
Y00954*
Y00954*
Y00953*
Y00953*
Y00952*
Y00952*
Y00951*
Y0095*
Y0095*
Y00949*
Y00949*
Y00948*
Y00948*
Y00947*
Y00947*
Y00946*
Y00946*
Y00945*
Y00945*
Y00944*
Y00943*
Y00943*
Y00942*
Y00942*
Y00941*
Y00941*
Y0094*
Y0094*
Y00939*
Y00939*
Y00938*
Y00938*
Y00937*
Y00936*
Y00936*
Y00935*
Y00935*
Y00934*
Y00934*
Y00933*
Y00933*
Y00932*
Y00932*
Y00931*
Y0093*
Y0093*
Y00929*
Y00929*
Y00928*
Y00928*
Y00927*
Y00927*
Y00926*
Y00926*
Y00925*
Y00925*
Y00924*
Y00923*
Y00923*
Y00922*
Y00922*
Y00921*
Y00921*
Y0092*
Y0092*
Y00919*
Y00919*
Y00918*
Y00918*
Y00917*
Y00916*
Y00916*
Y00915*
Y00915*
Y00914*
Y00914*
Y00913*
Y00913*
Y00912*
Y00912*
Y00911*
Y0091*
Y0091*
Y00909*
Y00909*
Y00908*
Y00908*
Y00907*
Y00907*
Y00906*
Y00906*
Y00905*
Y00905*
Y00904*
Y00903*
Y00903*
Y00902*
Y00902*
Y00901*
Y00901*
Y009*
Y009*
Y00899*
Y00899*
Y00898*
Y00897*
Y00897*
Y00896*
Y00896*
Y00895*
Y00895*
Y00894*
Y00894*
Y00893*
Y00893*
Y00892*
Y00892*
Y00891*
Y0089*
Y0089*
Y00889*
Y00889*
Y00888*
Y00888*
Y00887*
Y00887*
Y00886*
Y00886*
Y00885*
Y00885*
Y00884*
Y00883*
Y00883*
Y00882*
Y00882*
Y00881*
Y00881*
Y0088*
Y0088*
Y00879*
Y00879*
Y00878*
Y00877*
Y00877*
Y00876*
Y00876*
Y00875*
Y00875*
Y00874*
Y00874*
Y00873*
Y00873*
Y00872*
Y00872*
Y00871*
Y0087*
Y0087*
Y00869*
Y00869*
Y00868*
Y00868*
Y00867*
Y00867*
Y00866*
Y00866*
Y00865*
Y00865*
Y00864*
Y00863*
Y00863*
Y00862*
Y00862*
Y00861*
Y00861*
Y0086*
Y0086*
Y00859*
Y00859*
Y00858*
Y00857*
Y00857*
Y00856*
Y00856*
Y00855*
Y00855*
Y00854*
Y00854*
Y00853*
Y00853*
Y00852*
Y00852*
Y00851*
Y0085*
Y0085*
Y00849*
Y00849*
Y00848*
Y00848*
Y00847*
Y00847*
Y00846*
Y00846*
Y00845*
Y00845*
Y00844*
Y00843*
Y00843*
Y00842*
Y00842*
Y00841*
Y00841*
Y0084*
Y0084*
Y00839*
Y00839*
Y00838*
Y00837*
Y00837*
Y00836*
Y00836*
Y00835*
Y00835*
Y00834*
Y00834*
Y00833*
Y00833*
Y00832*
Y00832*
Y00831*
Y0083*
Y0083*
Y00829*
Y00829*
Y00828*
Y00828*
Y00827*
Y00827*
Y00826*
Y00826*
Y00825*
Y00825*
Y00824*
Y00823*
Y00823*
Y00822*
Y00822*
Y00821*
Y00821*
Y0082*
Y0082*
Y00819*
Y00819*
Y00818*
Y00817*
Y00817*
Y00816*
Y00816*
Y00815*
Y00815*
Y00814*
Y00814*
Y00813*
Y00813*
Y00812*
Y00812*
Y00811*
Y0081*
Y0081*
Y00809*
Y00809*
Y00808*
Y00808*
Y00807*
Y00807*
Y00806*
Y00806*
Y00805*
Y00805*
Y00804*
Y00803*
Y00803*
Y00802*
Y00802*
Y00801*
Y00801*
Y008*
Y008*
Y00799*
Y00799*
Y00798*
Y00797*
Y00797*
Y00796*
Y00796*
Y00795*
Y00795*
Y00794*
Y00794*
Y00793*
Y00793*
Y00792*
Y00792*
Y00791*
Y0079*
Y0079*
Y00789*
Y00789*
Y00788*
Y00788*
Y00787*
Y00787*
Y00786*
Y00786*
Y00785*
Y00785*
Y00784*
Y00783*
Y00783*
Y00782*
Y00782*
Y00781*
Y00781*
Y0078*
Y0078*
Y00779*
Y00779*
Y00778*
Y00777*
Y00777*
Y00776*
Y00776*
Y00775*
Y00775*
Y00774*
Y00774*
Y00773*
Y00773*
Y00772*
Y00772*
Y00771*
Y0077*
Y0077*
Y00769*
Y00769*
Y00768*
Y00768*
Y00767*
Y00767*
Y00766*
Y00766*
Y00765*
Y00765*
Y00764*
Y00763*
Y00763*
Y00762*
Y00762*
Y00761*
Y00761*
Y0076*
Y0076*
Y00759*
Y00759*
Y00758*
Y00757*
Y00757*
Y00756*
Y00756*
Y00755*
Y00755*
Y00754*
Y00754*
Y00753*
Y00753*
Y00752*
Y00752*
Y00751*
Y0075*
Y0075*
Y00749*
Y00749*
Y00748*
Y00748*
Y00747*
Y00747*
Y00746*
Y00746*
Y00745*
Y00745*
Y00744*
Y00743*
Y00743*
Y00742*
Y00742*
Y00741*
Y00741*
Y0074*
Y0074*
Y00739*
Y00739*
Y00738*
Y00737*
Y00737*
Y00736*
Y00736*
Y00735*
Y00735*
Y00734*
Y00734*
Y00733*
Y00733*
Y00732*
Y00732*
Y00731*
Y0073*
Y0073*
Y00729*
Y00729*
Y00728*
Y00728*
Y00727*
Y00727*
Y00726*
Y00726*
Y00725*
Y00725*
Y00724*
Y00723*
Y00723*
Y00722*
Y00722*
Y00721*
Y00721*
Y0072*
Y0072*
Y00719*
Y00719*
Y00718*
Y00717*
Y00717*
Y00716*
Y00716*
Y00715*
Y00715*
Y00714*
Y00714*
Y00713*
Y00713*
Y00712*
Y00712*
Y00711*
Y0071*
Y0071*
Y00709*
Y00709*
Y00708*
Y00708*
Y00707*
Y00707*
Y00706*
Y00706*
Y00705*
Y00704*
Y00704*
Y00703*
Y00703*
Y00702*
Y00702*
Y00701*
Y00701*
Y007*
Y007*
Y00699*
Y00699*
Y00698*
Y00697*
Y00697*
Y00696*
Y00696*
Y00695*
Y00695*
Y00694*
Y00694*
Y00693*
Y00693*
Y00692*
Y00692*
Y00691*
Y0069*
Y0069*
Y00689*
Y00689*
Y00688*
Y00688*
Y00687*
Y00687*
Y00686*
Y00686*
Y00685*
Y00684*
Y00684*
Y00683*
Y00683*
Y00682*
Y00682*
Y00681*
Y00681*
Y0068*
Y0068*
Y00679*
Y00679*
Y00678*
Y00677*
Y00677*
Y00676*
Y00676*
Y00675*
Y00675*
Y00674*
Y00674*
Y00673*
Y00673*
Y00672*
Y00672*
Y00671*
Y0067*
Y0067*
Y00669*
Y00669*
Y00668*
Y00668*
Y00667*
Y00667*
Y00666*
Y00666*
Y00665*
Y00664*
Y00664*
Y00663*
Y00663*
Y00662*
Y00662*
Y00661*
Y00661*
Y0066*
Y0066*
Y00659*
Y00659*
Y00658*
Y00657*
Y00657*
Y00656*
Y00656*
Y00655*
Y00655*
Y00654*
Y00654*
Y00653*
Y00653*
Y00652*
Y00652*
Y00651*
Y0065*
Y0065*
Y00649*
Y00649*
Y00648*
Y00648*
Y00647*
Y00647*
Y00646*
Y00646*
Y00645*
Y00644*
Y00644*
Y00643*
Y00643*
Y00642*
Y00642*
Y00641*
Y00641*
Y0064*
Y0064*
Y00639*
Y00639*
Y00638*
Y00637*
Y00637*
Y00636*
Y00636*
Y00635*
Y00635*
Y00634*
Y00634*
Y00633*
Y00633*
Y00632*
Y00632*
Y00631*
Y0063*
Y0063*
Y00629*
Y00629*
Y00628*
Y00628*
Y00627*
Y00627*
Y00626*
Y00626*
Y00625*
Y00624*
Y00624*
Y00623*
Y00623*
Y00622*
Y00622*
Y00621*
Y00621*
Y0062*
Y0062*
Y00619*
Y00619*
Y00618*
Y00617*
Y00617*
Y00616*
Y00616*
Y00615*
Y00615*
Y00614*
Y00614*
Y00613*
Y00613*
Y00612*
Y00612*
Y00611*
Y0061*
Y0061*
Y00609*
Y00609*
Y00608*
Y00608*
Y00607*
Y00607*
Y00606*
Y00606*
Y00605*
Y00604*
Y00604*
Y00603*
Y00603*
Y00602*
Y00602*
Y00601*
Y00601*
Y006*
Y006*
Y00599*
Y00599*
Y00598*
Y00597*
Y00597*
Y00596*
Y00596*
Y00595*
Y00595*
Y00594*
Y00594*
Y00593*
Y00593*
Y00592*
Y00592*
Y00591*
Y0059*
Y0059*
Y00589*
Y00589*
Y00588*
Y00588*
Y00587*
Y00587*
Y00586*
Y00586*
Y00585*
Y00584*
Y00584*
Y00583*
Y00583*
Y00582*
Y00582*
Y00581*
Y00581*
Y0058*
Y0058*
Y00579*
Y00579*
Y00578*
Y00577*
Y00577*
Y00576*
Y00576*
Y00575*
Y00575*
Y00574*
Y00574*
Y00573*
Y00573*
Y00572*
Y00572*
Y00571*
Y0057*
Y0057*
Y00569*
Y00569*
Y00568*
Y00568*
Y00567*
Y00567*
Y00566*
Y00566*
Y00565*
Y00564*
Y00564*
Y00563*
Y00563*
Y00562*
Y00562*
Y00561*
Y00561*
Y0056*
Y0056*
Y00559*
X05906*
Y0056*
Y0056*
Y00561*
Y00561*
Y00562*
Y00562*
Y00563*
Y00563*
Y00564*
Y00564*
Y00565*
Y00566*
Y00566*
Y00567*
Y00567*
Y00568*
Y00568*
Y00569*
Y00569*
Y0057*
Y0057*
Y00571*
Y00572*
Y00572*
Y00573*
Y00573*
Y00574*
Y00574*
Y00575*
Y00575*
Y00576*
Y00576*
Y00577*
Y00577*
Y00578*
Y00579*
Y00579*
Y0058*
Y0058*
Y00581*
Y00581*
Y00582*
Y00582*
Y00583*
Y00583*
Y00584*
Y00584*
Y00585*
Y00586*
Y00586*
Y00587*
Y00587*
Y00588*
Y00588*
Y00589*
Y00589*
Y0059*
Y0059*
Y00591*
Y00592*
Y00592*
Y00593*
Y00593*
Y00594*
Y00594*
Y00595*
Y00595*
Y00596*
Y00596*
Y00597*
Y00597*
Y00598*
Y00599*
Y00599*
Y006*
Y006*
Y00601*
Y00601*
Y00602*
Y00602*
Y00603*
Y00603*
Y00604*
Y00604*
Y00605*
Y00606*
Y00606*
Y00607*
Y00607*
Y00608*
Y00608*
Y00609*
Y00609*
Y0061*
Y0061*
Y00611*
Y00612*
Y00612*
Y00613*
Y00613*
Y00614*
Y00614*
Y00615*
Y00615*
Y00616*
Y00616*
Y00617*
Y00617*
Y00618*
Y00619*
Y00619*
Y0062*
Y0062*
Y00621*
Y00621*
Y00622*
Y00622*
Y00623*
Y00623*
Y00624*
Y00624*
Y00625*
Y00626*
Y00626*
Y00627*
Y00627*
Y00628*
Y00628*
Y00629*
Y00629*
Y0063*
Y0063*
Y00631*
Y00632*
Y00632*
Y00633*
Y00633*
Y00634*
Y00634*
Y00635*
Y00635*
Y00636*
Y00636*
Y00637*
Y00637*
Y00638*
Y00639*
Y00639*
Y0064*
Y0064*
Y00641*
Y00641*
Y00642*
Y00642*
Y00643*
Y00643*
Y00644*
Y00644*
Y00645*
Y00646*
Y00646*
Y00647*
Y00647*
Y00648*
Y00648*
Y00649*
Y00649*
Y0065*
Y0065*
Y00651*
Y00652*
Y00652*
Y00653*
Y00653*
Y00654*
Y00654*
Y00655*
Y00655*
Y00656*
Y00656*
Y00657*
Y00657*
Y00658*
Y00659*
Y00659*
Y0066*
Y0066*
Y00661*
Y00661*
Y00662*
Y00662*
Y00663*
Y00663*
Y00664*
Y00664*
Y00665*
Y00666*
Y00666*
Y00667*
Y00667*
Y00668*
Y00668*
Y00669*
Y00669*
Y0067*
Y0067*
Y00671*
Y00672*
Y00672*
Y00673*
Y00673*
Y00674*
Y00674*
Y00675*
Y00675*
Y00676*
Y00676*
Y00677*
Y00677*
Y00678*
Y00679*
Y00679*
Y0068*
Y0068*
Y00681*
Y00681*
Y00682*
Y00682*
Y00683*
Y00683*
Y00684*
Y00684*
Y00685*
Y00686*
Y00686*
Y00687*
Y00687*
Y00688*
Y00688*
Y00689*
Y00689*
Y0069*
Y0069*
Y00691*
Y00692*
Y00692*
Y00693*
Y00693*
Y00694*
Y00694*
Y00695*
Y00695*
Y00696*
Y00696*
Y00697*
Y00697*
Y00698*
Y00699*
Y00699*
Y007*
Y007*
Y00701*
Y00701*
Y00702*
Y00702*
Y00703*
Y00703*
Y00704*
Y00704*
Y00705*
Y00706*
Y00706*
Y00707*
Y00707*
Y00708*
Y00708*
Y00709*
Y00709*
Y0071*
Y0071*
Y00711*
Y00712*
Y00712*
Y00713*
Y00713*
Y00714*
Y00714*
Y00715*
Y00715*
Y00716*
Y00716*
Y00717*
Y00717*
Y00718*
Y00719*
Y00719*
Y0072*
Y0072*
Y00721*
Y00721*
Y00722*
Y00722*
Y00723*
Y00723*
Y00724*
Y00725*
Y00725*
Y00726*
Y00726*
Y00727*
Y00727*
Y00728*
Y00728*
Y00729*
Y00729*
Y0073*
Y0073*
Y00731*
Y00732*
Y00732*
Y00733*
Y00733*
Y00734*
Y00734*
Y00735*
Y00735*
Y00736*
Y00736*
Y00737*
Y00737*
Y00738*
Y00739*
Y00739*
Y0074*
Y0074*
Y00741*
Y00741*
Y00742*
Y00742*
Y00743*
Y00743*
Y00744*
Y00745*
Y00745*
Y00746*
Y00746*
Y00747*
Y00747*
Y00748*
Y00748*
Y00749*
Y00749*
Y0075*
Y0075*
Y00751*
Y00752*
Y00752*
Y00753*
Y00753*
Y00754*
Y00754*
Y00755*
Y00755*
Y00756*
Y00756*
Y00757*
Y00757*
Y00758*
Y00759*
Y00759*
Y0076*
Y0076*
Y00761*
Y00761*
Y00762*
Y00762*
Y00763*
Y00763*
Y00764*
Y00765*
Y00765*
Y00766*
Y00766*
Y00767*
Y00767*
Y00768*
Y00768*
Y00769*
Y00769*
Y0077*
Y0077*
Y00771*
Y00772*
Y00772*
Y00773*
Y00773*
Y00774*
Y00774*
Y00775*
Y00775*
Y00776*
Y00776*
Y00777*
Y00777*
Y00778*
Y00779*
Y00779*
Y0078*
Y0078*
Y00781*
Y00781*
Y00782*
Y00782*
Y00783*
Y00783*
Y00784*
Y00785*
Y00785*
Y00786*
Y00786*
Y00787*
Y00787*
Y00788*
Y00788*
Y00789*
Y00789*
Y0079*
Y0079*
Y00791*
Y00792*
Y00792*
Y00793*
Y00793*
Y00794*
Y00794*
Y00795*
Y00795*
Y00796*
Y00796*
Y00797*
Y00797*
Y00798*
Y00799*
Y00799*
Y008*
Y008*
Y00801*
Y00801*
Y00802*
Y00802*
Y00803*
Y00803*
Y00804*
Y00805*
Y00805*
Y00806*
Y00806*
Y00807*
Y00807*
Y00808*
Y00808*
Y00809*
Y00809*
Y0081*
Y0081*
Y00811*
Y00812*
Y00812*
Y00813*
Y00813*
Y00814*
Y00814*
Y00815*
Y00815*
Y00816*
Y00816*
Y00817*
Y00817*
Y00818*
Y00819*
Y00819*
Y0082*
Y0082*
Y00821*
Y00821*
Y00822*
Y00822*
Y00823*
Y00823*
Y00824*
Y00825*
Y00825*
Y00826*
Y00826*
Y00827*
Y00827*
Y00828*
Y00828*
Y00829*
Y00829*
Y0083*
Y0083*
Y00831*
Y00832*
Y00832*
Y00833*
Y00833*
Y00834*
Y00834*
Y00835*
Y00835*
Y00836*
Y00836*
Y00837*
Y00837*
Y00838*
Y00839*
Y00839*
Y0084*
Y0084*
Y00841*
Y00841*
Y00842*
Y00842*
Y00843*
Y00843*
Y00844*
Y00845*
Y00845*
Y00846*
Y00846*
Y00847*
Y00847*
Y00848*
Y00848*
Y00849*
Y00849*
Y0085*
Y0085*
Y00851*
Y00852*
Y00852*
Y00853*
Y00853*
Y00854*
Y00854*
Y00855*
Y00855*
Y00856*
Y00856*
Y00857*
Y00857*
Y00858*
Y00859*
Y00859*
Y0086*
Y0086*
Y00861*
Y00861*
Y00862*
Y00862*
Y00863*
Y00863*
Y00864*
Y00865*
Y00865*
Y00866*
Y00866*
Y00867*
Y00867*
Y00868*
Y00868*
Y00869*
Y00869*
Y0087*
Y0087*
Y00871*
Y00872*
Y00872*
Y00873*
Y00873*
Y00874*
Y00874*
Y00875*
Y00875*
Y00876*
Y00876*
Y00877*
Y00877*
Y00878*
Y00879*
Y00879*
Y0088*
Y0088*
Y00881*
Y00881*
Y00882*
Y00882*
Y00883*
Y00883*
Y00884*
Y00885*
Y00885*
Y00886*
Y00886*
Y00887*
Y00887*
Y00888*
Y00888*
Y00889*
Y00889*
Y0089*
Y0089*
Y00891*
Y00892*
Y00892*
Y00893*
Y00893*
Y00894*
Y00894*
Y00895*
Y00895*
Y00896*
Y00896*
Y00897*
Y00897*
Y00898*
Y00899*
Y00899*
Y009*
Y009*
Y00901*
Y00901*
Y00902*
Y00902*
Y00903*
Y00903*
Y00904*
Y00905*
Y00905*
Y00906*
Y00906*
Y00907*
Y00907*
Y00908*
Y00908*
Y00909*
Y00909*
Y0091*
Y0091*
Y00911*
Y00912*
Y00912*
Y00913*
Y00913*
Y00914*
Y00914*
Y00915*
Y00915*
Y00916*
Y00916*
Y00917*
Y00918*
Y00918*
Y00919*
Y00919*
Y0092*
Y0092*
Y00921*
Y00921*
Y00922*
Y00922*
Y00923*
Y00923*
Y00924*
Y00925*
Y00925*
Y00926*
Y00926*
Y00927*
Y00927*
Y00928*
Y00928*
Y00929*
Y00929*
Y0093*
Y0093*
Y00931*
Y00932*
Y00932*
Y00933*
Y00933*
Y00934*
Y00934*
Y00935*
Y00935*
Y00936*
Y00936*
Y00937*
Y00938*
Y00938*
Y00939*
Y00939*
Y0094*
Y0094*
Y00941*
Y00941*
Y00942*
Y00942*
Y00943*
Y00943*
Y00944*
Y00945*
Y00945*
Y00946*
Y00946*
Y00947*
Y00947*
Y00948*
Y00948*
Y00949*
Y00949*
Y0095*
Y0095*
Y00951*
Y00952*
Y00952*
Y00953*
Y00953*
Y00954*
Y00954*
Y00955*
Y00955*
Y00956*
Y00956*
Y00957*
Y00958*
Y00958*
Y00959*
Y00959*
Y0096*
Y0096*
Y00961*
Y00961*
Y00962*
Y00962*
Y00963*
Y00963*
Y00964*
Y00965*
Y00965*
Y00966*
Y00966*
Y00967*
Y00967*
Y00968*
Y00968*
Y00969*
Y00969*
Y0097*
Y0097*
Y00971*
Y00972*
Y00972*
Y00973*
Y00973*
Y00974*
Y00974*
Y00975*
Y00975*
Y00976*
Y00976*
Y00977*
Y00978*
Y00978*
Y00979*
Y00979*
Y0098*
Y0098*
Y00981*
Y00981*
Y00982*
Y00982*
Y00983*
Y00983*
Y00984*
Y00985*
Y00985*
Y00986*
Y00986*
Y00987*
Y00987*
Y00988*
Y00988*
Y00989*
Y00989*
Y0099*
Y0099*
Y00991*
Y00992*
Y00992*
Y00993*
Y00993*
Y00994*
Y00994*
Y00995*
Y00995*
Y00996*
Y00996*
Y00997*
Y00998*
Y00998*
Y00999*
Y00999*
Y01*
Y01*
Y01001*
Y01001*
Y01002*
Y01002*
Y01003*
Y01003*
Y01004*
Y01005*
Y01005*
Y01006*
Y01006*
Y01007*
Y01007*
Y01008*
Y01008*
Y01009*
Y01009*
Y0101*
Y0101*
Y01011*
Y01012*
Y01012*
Y01013*
Y01013*
Y01014*
Y01014*
Y01015*
Y01015*
Y01016*
Y01016*
Y01017*
Y01018*
Y01018*
Y01019*
Y01019*
Y0102*
Y0102*
Y01021*
Y01021*
Y01022*
Y01022*
Y01023*
Y01023*
Y01024*
Y01025*
Y01025*
Y01026*
Y01026*
Y01027*
Y01027*
Y01028*
Y01028*
Y01029*
Y01029*
Y0103*
Y0103*
Y01031*
Y01032*
Y01032*
Y01033*
Y01033*
Y01034*
Y01034*
Y01035*
Y01035*
Y01036*
Y01036*
Y01037*
Y01038*
Y01038*
Y01039*
Y01039*
Y0104*
Y0104*
Y01041*
Y01041*
Y01042*
Y01042*
Y01043*
Y01043*
Y01044*
Y01045*
Y01045*
Y01046*
Y01046*
Y01047*
Y01047*
Y01048*
Y01048*
Y01049*
Y01049*
Y0105*
Y0105*
Y01051*
Y01052*
Y01052*
Y01053*
Y01053*
Y01054*
Y01054*
Y01055*
Y01055*
Y01056*
Y01056*
Y01057*
Y01058*
Y01058*
Y01059*
Y01059*
Y0106*
Y0106*
Y01061*
Y01061*
Y01062*
Y01062*
Y01063*
Y01063*
Y01064*
Y01065*
Y01065*
Y01066*
Y01066*
Y01067*
Y01067*
Y01068*
Y01068*
Y01069*
Y01069*
Y0107*
Y0107*
Y01071*
Y01072*
Y01072*
Y01073*
Y01073*
Y01074*
Y01074*
Y01075*
Y01075*
Y01076*
Y01076*
Y01077*
Y01078*
Y01078*
Y01079*
Y01079*
Y0108*
Y0108*
Y01081*
Y01081*
Y01082*
Y01082*
Y01083*
Y01083*
Y01084*
Y01085*
Y01085*
Y01086*
Y01086*
Y01087*
Y01087*
Y01088*
Y01088*
Y01089*
Y01089*
Y0109*
Y01091*
Y01091*
Y01092*
Y01092*
Y01093*
Y01093*
Y01094*
Y01094*
Y01095*
Y01095*
Y01096*
Y01096*
Y01097*
Y01098*
Y01098*
Y01099*
Y01099*
Y011*
Y011*
Y01101*
Y01101*
Y01102*
Y01102*
Y01103*
Y01103*
Y01104*
Y01105*
Y01105*
Y01106*
Y01106*
Y01107*
Y01107*
Y01108*
Y01108*
Y01109*
Y01109*
Y0111*
Y01111*
Y01111*
Y01112*
Y01112*
Y01113*
Y01113*
Y01114*
Y01114*
Y01115*
Y01115*
Y01116*
Y01116*
Y01117*
Y01118*
Y01118*
Y01119*
Y01119*
Y0112*
Y0112*
Y01121*
Y01121*
Y01122*
Y01122*
Y01123*
Y01123*
Y01124*
Y01125*
Y01125*
Y01126*
Y01126*
Y01127*
Y01127*
Y01128*
Y01128*
Y01129*
Y01129*
Y0113*
Y01131*
Y01131*
Y01132*
Y01132*
Y01133*
Y01133*
Y01134*
Y01134*
Y01135*
Y01135*
Y01136*
Y01136*
Y01137*
Y01138*
Y01138*
Y01139*
Y01139*
Y0114*
Y0114*
Y01141*
Y01141*
Y01142*
Y01142*
Y01143*
Y01143*
Y01144*
X05905*
Y01145*
Y01145*
Y01146*
Y01146*
Y01147*
X05905*
Y01147*
Y01148*
X05904*
Y01148*
Y01149*
X05904*
Y01149*
Y0115*
X05903*
Y01151*
X05903*
Y01151*
Y01152*
X05902*
Y01152*
X05902*
Y01153*
X05901*
Y01153*
X059*
Y01154*
X05899*
Y01154*
X05898*
Y01155*
X05897*
Y01155*
X05896*
Y01156*
X05894*
Y01156*
X05825*
Y01157*
Y01158*
Y01158*
Y01159*
Y01159*
Y0116*
Y0116*
Y01161*
Y01161*
Y01162*
Y01162*
Y01163*
Y01163*
Y01164*
Y01165*
Y01165*
Y01166*
Y01166*
Y01167*
Y01167*
Y01168*
Y01168*
Y01169*
Y01169*
Y0117*
Y01171*
Y01171*
Y01172*
Y01172*
Y01173*
Y01173*
Y01174*
Y01174*
Y01175*
Y01175*
Y01176*
Y01176*
Y01177*
X05894*
Y01176*
G37*
%LNtimingcard_pcb-2*%
%LPC*%
G36*
X06391Y01045D02*
X0639D01*
Y01045*
X06389*
Y01045*
X06326*
Y01045*
X06323*
Y01044*
X06322*
Y01043*
X06321*
Y01043*
X0632*
Y01042*
X06319*
Y01042*
X06319*
Y01041*
X06318*
Y01041*
X06318*
Y0104*
X06317*
Y0104*
X06317*
Y01039*
X06316*
Y01039*
X06316*
Y01038*
X06315*
Y01038*
X06315*
Y01037*
X06314*
Y01036*
X06314*
Y01036*
X06313*
Y01035*
X06312*
Y01035*
X06312*
Y01034*
X06311*
Y01034*
X06311*
Y01033*
X0631*
Y01033*
X0631*
Y01032*
X06309*
Y01032*
X06309*
Y01031*
X06308*
Y0103*
X06308*
Y0103*
X06307*
Y01029*
X06306*
Y01029*
X06306*
Y01028*
X06305*
Y01028*
X06305*
Y01027*
Y01027*
Y01026*
X06304*
Y01026*
Y01025*
Y01025*
Y01024*
Y01023*
X06304*
Y01023*
Y01022*
Y01022*
Y01021*
Y01021*
Y0102*
Y0102*
Y01019*
Y01019*
Y01018*
Y01018*
Y01017*
Y01016*
Y01016*
Y01015*
Y01015*
Y01014*
Y01014*
Y01013*
Y01013*
Y01012*
Y01012*
Y01011*
Y0101*
Y0101*
Y01009*
Y01009*
Y01008*
Y01008*
Y01007*
Y01007*
Y01006*
Y01006*
Y01005*
Y01005*
Y01004*
Y01003*
Y01003*
Y01002*
Y01002*
Y01001*
Y01001*
Y01*
Y01*
Y00999*
Y00999*
Y00998*
Y00998*
Y00997*
Y00996*
Y00996*
Y00995*
Y00995*
Y00994*
Y00994*
Y00993*
Y00993*
Y00992*
Y00992*
Y00991*
Y0099*
Y0099*
Y00989*
Y00989*
Y00988*
Y00988*
Y00987*
Y00987*
Y00986*
Y00986*
Y00985*
Y00985*
Y00984*
Y00983*
Y00983*
Y00982*
Y00982*
Y00981*
Y00981*
Y0098*
Y0098*
Y00979*
Y00979*
Y00978*
Y00978*
Y00977*
Y00976*
Y00976*
Y00975*
Y00975*
Y00974*
Y00974*
Y00973*
Y00973*
Y00972*
Y00972*
Y00971*
Y0097*
Y0097*
Y00969*
Y00969*
Y00968*
Y00968*
Y00967*
Y00967*
Y00966*
Y00966*
Y00965*
Y00965*
Y00964*
Y00963*
Y00963*
Y00962*
Y00962*
Y00961*
Y00961*
Y0096*
Y0096*
Y00959*
Y00959*
Y00958*
Y00958*
Y00957*
Y00956*
Y00956*
Y00955*
Y00955*
Y00954*
Y00954*
Y00953*
Y00953*
Y00952*
Y00952*
Y00951*
Y0095*
Y0095*
Y00949*
Y00949*
Y00948*
X06304*
Y00948*
Y00947*
Y00947*
Y00946*
Y00946*
X06305*
Y00945*
Y00945*
X06305*
Y00944*
Y00943*
X06306*
Y00943*
X06306*
Y00942*
X06307*
Y00942*
X06308*
Y00941*
X06308*
Y00941*
X06309*
Y0094*
X06309*
Y0094*
X0631*
Y00939*
X0631*
Y00939*
X06311*
Y00938*
X06311*
Y00938*
X06312*
Y00937*
X06312*
Y00936*
X06313*
Y00936*
X06314*
Y00935*
X06314*
Y00935*
X06315*
Y00934*
X06315*
Y00934*
X06316*
Y00933*
X06316*
Y00933*
X06317*
Y00932*
X06317*
Y00932*
X06318*
Y00931*
X06318*
Y0093*
X06319*
Y0093*
X06319*
Y00929*
X0632*
Y00929*
X06321*
Y00928*
X06322*
Y00928*
X06324*
Y00927*
X06392*
Y00928*
X06393*
Y00928*
X06394*
Y00929*
Y00929*
X06394*
Y0093*
Y0093*
Y00931*
Y00932*
Y00932*
Y00933*
Y00933*
Y00934*
Y00934*
Y00935*
Y00935*
Y00936*
Y00936*
Y00937*
Y00938*
Y00938*
Y00939*
Y00939*
Y0094*
Y0094*
Y00941*
Y00941*
Y00942*
Y00942*
Y00943*
Y00943*
Y00944*
Y00945*
Y00945*
Y00946*
Y00946*
Y00947*
Y00947*
Y00948*
Y00948*
Y00949*
Y00949*
Y0095*
Y0095*
Y00951*
Y00952*
Y00952*
Y00953*
X06394*
Y00953*
Y00954*
X06393*
Y00954*
X06392*
Y00955*
X06334*
Y00955*
X06334*
Y00956*
Y00956*
Y00957*
Y00958*
Y00958*
Y00959*
Y00959*
Y0096*
Y0096*
Y00961*
Y00961*
Y00962*
Y00962*
Y00963*
Y00963*
Y00964*
Y00965*
Y00965*
Y00966*
Y00966*
Y00967*
Y00967*
Y00968*
Y00968*
Y00969*
Y00969*
Y0097*
Y0097*
Y00971*
Y00972*
Y00972*
Y00973*
Y00973*
Y00974*
X06334*
Y00974*
X06384*
Y00975*
X06385*
Y00975*
Y00976*
X06385*
Y00976*
Y00977*
Y00978*
Y00978*
Y00979*
Y00979*
Y0098*
Y0098*
Y00981*
Y00981*
Y00982*
Y00982*
Y00983*
Y00983*
Y00984*
Y00985*
Y00985*
Y00986*
Y00986*
Y00987*
Y00987*
Y00988*
Y00988*
Y00989*
Y00989*
Y0099*
Y0099*
Y00991*
Y00992*
Y00992*
Y00993*
Y00993*
Y00994*
Y00994*
Y00995*
Y00995*
Y00996*
X06385*
Y00996*
Y00997*
X06384*
Y00998*
X06334*
Y00998*
X06334*
Y00999*
Y00999*
Y01*
Y01*
Y01001*
Y01001*
Y01002*
Y01002*
Y01003*
Y01003*
Y01004*
Y01005*
Y01005*
Y01006*
Y01006*
Y01007*
Y01007*
Y01008*
Y01008*
Y01009*
Y01009*
Y0101*
Y0101*
Y01011*
Y01012*
Y01012*
Y01013*
Y01013*
Y01014*
Y01014*
Y01015*
Y01015*
Y01016*
Y01016*
Y01017*
X06334*
Y01018*
X06392*
Y01018*
X06393*
Y01019*
X06394*
Y01019*
X06394*
Y0102*
Y0102*
Y01021*
Y01021*
Y01022*
Y01022*
Y01023*
Y01023*
Y01024*
Y01025*
Y01025*
Y01026*
Y01026*
Y01027*
Y01027*
Y01028*
Y01028*
Y01029*
Y01029*
Y0103*
Y0103*
Y01031*
Y01032*
Y01032*
Y01033*
Y01033*
Y01034*
Y01034*
Y01035*
Y01035*
Y01036*
Y01036*
Y01037*
Y01038*
Y01038*
Y01039*
Y01039*
Y0104*
Y0104*
Y01041*
Y01041*
Y01042*
Y01042*
X06394*
Y01043*
Y01043*
X06393*
Y01044*
X06392*
Y01045*
X06391*
Y01045*
G37*
G36*
X06115D02*
X06113D01*
Y01045*
X06113*
Y01045*
X0603*
Y01045*
X06028*
Y01044*
X06028*
Y01043*
Y01043*
X06027*
Y01042*
Y01042*
Y01041*
Y01041*
Y0104*
Y0104*
Y01039*
Y01039*
Y01038*
Y01038*
Y01037*
Y01036*
Y01036*
Y01035*
Y01035*
Y01034*
Y01034*
Y01033*
Y01033*
Y01032*
Y01032*
Y01031*
Y0103*
Y0103*
Y01029*
Y01029*
Y01028*
Y01028*
Y01027*
Y01027*
Y01026*
Y01026*
Y01025*
Y01025*
Y01024*
Y01023*
Y01023*
Y01022*
Y01022*
Y01021*
Y01021*
Y0102*
Y0102*
Y01019*
Y01019*
Y01018*
X06028*
Y01018*
X06028*
Y01017*
X06029*
Y01016*
X0603*
Y01016*
X06056*
Y01015*
X06056*
Y01015*
X06057*
Y01014*
Y01014*
X06057*
Y01013*
Y01013*
Y01012*
Y01012*
Y01011*
Y0101*
Y0101*
Y01009*
Y01009*
Y01008*
Y01008*
Y01007*
Y01007*
Y01006*
Y01006*
Y01005*
Y01005*
Y01004*
Y01003*
Y01003*
Y01002*
Y01002*
Y01001*
Y01001*
Y01*
Y01*
Y00999*
Y00999*
Y00998*
Y00998*
Y00997*
Y00996*
Y00996*
Y00995*
Y00995*
Y00994*
Y00994*
Y00993*
Y00993*
Y00992*
Y00992*
Y00991*
Y0099*
Y0099*
Y00989*
Y00989*
Y00988*
Y00988*
Y00987*
Y00987*
Y00986*
Y00986*
Y00985*
Y00985*
Y00984*
Y00983*
Y00983*
Y00982*
Y00982*
Y00981*
Y00981*
Y0098*
Y0098*
Y00979*
Y00979*
Y00978*
Y00978*
Y00977*
Y00976*
Y00976*
Y00975*
Y00975*
Y00974*
Y00974*
Y00973*
Y00973*
Y00972*
Y00972*
Y00971*
Y0097*
Y0097*
Y00969*
Y00969*
Y00968*
Y00968*
Y00967*
Y00967*
Y00966*
Y00966*
Y00965*
Y00965*
Y00964*
Y00963*
Y00963*
Y00962*
Y00962*
Y00961*
Y00961*
Y0096*
Y0096*
Y00959*
Y00959*
Y00958*
Y00958*
Y00957*
Y00956*
Y00956*
Y00955*
Y00955*
Y00954*
Y00954*
Y00953*
Y00953*
Y00952*
Y00952*
Y00951*
Y0095*
Y0095*
Y00949*
Y00949*
Y00948*
Y00948*
Y00947*
Y00947*
Y00946*
Y00946*
Y00945*
Y00945*
Y00944*
Y00943*
Y00943*
Y00942*
Y00942*
Y00941*
Y00941*
Y0094*
Y0094*
Y00939*
Y00939*
Y00938*
Y00938*
Y00937*
Y00936*
Y00936*
Y00935*
Y00935*
Y00934*
Y00934*
Y00933*
Y00933*
Y00932*
Y00932*
Y00931*
Y0093*
Y0093*
Y00929*
Y00929*
X06058*
Y00928*
X06058*
Y00928*
X06059*
Y00927*
X06085*
Y00928*
X06086*
Y00928*
X06086*
Y00929*
Y00929*
Y0093*
X06087*
Y0093*
Y00931*
Y00932*
Y00932*
Y00933*
Y00933*
Y00934*
Y00934*
Y00935*
Y00935*
Y00936*
Y00936*
Y00937*
Y00938*
Y00938*
Y00939*
Y00939*
Y0094*
Y0094*
Y00941*
Y00941*
Y00942*
Y00942*
Y00943*
Y00943*
Y00944*
Y00945*
Y00945*
Y00946*
Y00946*
Y00947*
Y00947*
Y00948*
Y00948*
Y00949*
Y00949*
Y0095*
Y0095*
Y00951*
Y00952*
Y00952*
Y00953*
Y00953*
Y00954*
Y00954*
Y00955*
Y00955*
Y00956*
Y00956*
Y00957*
Y00958*
Y00958*
Y00959*
Y00959*
Y0096*
Y0096*
Y00961*
Y00961*
Y00962*
Y00962*
Y00963*
Y00963*
Y00964*
Y00965*
Y00965*
Y00966*
Y00966*
Y00967*
Y00967*
Y00968*
Y00968*
Y00969*
Y00969*
Y0097*
Y0097*
Y00971*
Y00972*
Y00972*
Y00973*
Y00973*
Y00974*
Y00974*
Y00975*
Y00975*
Y00976*
Y00976*
Y00977*
Y00978*
Y00978*
Y00979*
Y00979*
Y0098*
Y0098*
Y00981*
Y00981*
Y00982*
Y00982*
Y00983*
Y00983*
Y00984*
Y00985*
Y00985*
Y00986*
Y00986*
Y00987*
Y00987*
Y00988*
Y00988*
Y00989*
Y00989*
Y0099*
Y0099*
Y00991*
Y00992*
Y00992*
Y00993*
Y00993*
Y00994*
Y00994*
Y00995*
Y00995*
Y00996*
Y00996*
Y00997*
Y00998*
Y00998*
Y00999*
Y00999*
Y01*
Y01*
Y01001*
Y01001*
Y01002*
Y01002*
Y01003*
Y01003*
Y01004*
Y01005*
Y01005*
Y01006*
Y01006*
Y01007*
Y01007*
Y01008*
Y01008*
Y01009*
Y01009*
Y0101*
Y0101*
Y01011*
Y01012*
Y01012*
Y01013*
Y01013*
Y01014*
Y01014*
Y01015*
X06088*
Y01015*
X06088*
Y01016*
X06114*
Y01016*
X06116*
Y01017*
X06116*
Y01018*
X06117*
Y01018*
Y01019*
Y01019*
X06117*
Y0102*
Y0102*
Y01021*
Y01021*
Y01022*
Y01022*
Y01023*
Y01023*
Y01024*
Y01025*
Y01025*
Y01026*
Y01026*
Y01027*
Y01027*
Y01028*
Y01028*
Y01029*
Y01029*
Y0103*
Y0103*
Y01031*
Y01032*
Y01032*
Y01033*
Y01033*
Y01034*
Y01034*
Y01035*
Y01035*
Y01036*
Y01036*
Y01037*
Y01038*
Y01038*
Y01039*
Y01039*
Y0104*
Y0104*
Y01041*
Y01041*
Y01042*
X06117*
Y01042*
Y01043*
Y01043*
X06116*
Y01044*
X06116*
Y01045*
X06115*
Y01045*
G37*
G36*
X06252D02*
X0617D01*
Y01045*
X06168*
Y01044*
X06168*
Y01043*
Y01043*
X06167*
Y01042*
Y01042*
Y01041*
Y01041*
Y0104*
Y0104*
Y01039*
Y01039*
Y01038*
Y01038*
Y01037*
Y01036*
Y01036*
Y01035*
Y01035*
Y01034*
Y01034*
Y01033*
Y01033*
Y01032*
Y01032*
Y01031*
Y0103*
Y0103*
Y01029*
Y01029*
Y01028*
Y01028*
Y01027*
Y01027*
Y01026*
Y01026*
Y01025*
Y01025*
Y01024*
Y01023*
Y01023*
Y01022*
Y01022*
Y01021*
Y01021*
Y0102*
Y0102*
Y01019*
Y01019*
Y01018*
Y01018*
Y01017*
Y01016*
Y01016*
Y01015*
Y01015*
Y01014*
Y01014*
Y01013*
Y01013*
Y01012*
Y01012*
Y01011*
Y0101*
Y0101*
Y01009*
Y01009*
Y01008*
Y01008*
Y01007*
Y01007*
Y01006*
Y01006*
Y01005*
Y01005*
Y01004*
Y01003*
Y01003*
Y01002*
Y01002*
Y01001*
Y01001*
Y01*
Y01*
Y00999*
Y00999*
Y00998*
Y00998*
Y00997*
Y00996*
Y00996*
Y00995*
Y00995*
Y00994*
Y00994*
Y00993*
Y00993*
Y00992*
Y00992*
Y00991*
Y0099*
Y0099*
Y00989*
Y00989*
Y00988*
Y00988*
Y00987*
Y00987*
Y00986*
Y00986*
Y00985*
Y00985*
Y00984*
Y00983*
Y00983*
Y00982*
Y00982*
Y00981*
Y00981*
Y0098*
Y0098*
Y00979*
Y00979*
Y00978*
Y00978*
Y00977*
Y00976*
Y00976*
Y00975*
Y00975*
Y00974*
Y00974*
Y00973*
Y00973*
Y00972*
Y00972*
Y00971*
Y0097*
Y0097*
Y00969*
Y00969*
Y00968*
Y00968*
Y00967*
Y00967*
Y00966*
Y00966*
Y00965*
Y00965*
Y00964*
Y00963*
Y00963*
Y00962*
Y00962*
Y00961*
Y00961*
Y0096*
Y0096*
Y00959*
Y00959*
Y00958*
Y00958*
Y00957*
Y00956*
Y00956*
Y00955*
Y00955*
Y00954*
Y00954*
Y00953*
Y00953*
Y00952*
Y00952*
Y00951*
Y0095*
Y0095*
Y00949*
Y00949*
Y00948*
Y00948*
Y00947*
Y00947*
Y00946*
Y00946*
Y00945*
Y00945*
Y00944*
Y00943*
Y00943*
Y00942*
Y00942*
Y00941*
Y00941*
Y0094*
Y0094*
Y00939*
Y00939*
Y00938*
Y00938*
Y00937*
Y00936*
Y00936*
Y00935*
Y00935*
Y00934*
Y00934*
Y00933*
Y00933*
Y00932*
Y00932*
Y00931*
Y0093*
Y0093*
Y00929*
Y00929*
X06168*
Y00928*
Y00928*
X06169*
Y00927*
X06195*
Y00928*
X06196*
Y00928*
X06196*
Y00929*
Y00929*
X06197*
Y0093*
Y0093*
Y00931*
Y00932*
Y00932*
Y00933*
Y00933*
Y00934*
Y00934*
Y00935*
Y00935*
Y00936*
Y00936*
Y00937*
Y00938*
Y00938*
Y00939*
Y00939*
Y0094*
Y0094*
Y00941*
Y00941*
Y00942*
Y00942*
Y00943*
Y00943*
Y00944*
Y00945*
Y00945*
Y00946*
Y00946*
Y00947*
Y00947*
Y00948*
Y00948*
Y00949*
Y00949*
Y0095*
Y0095*
Y00951*
Y00952*
Y00952*
Y00953*
Y00953*
Y00954*
Y00954*
Y00955*
Y00955*
Y00956*
Y00956*
Y00957*
Y00958*
Y00958*
Y00959*
Y00959*
Y0096*
Y0096*
Y00961*
Y00961*
Y00962*
Y00962*
Y00963*
Y00963*
Y00964*
Y00965*
Y00965*
Y00966*
Y00966*
Y00967*
Y00967*
Y00968*
Y00968*
Y00969*
Y00969*
Y0097*
Y0097*
Y00971*
Y00972*
Y00972*
Y00973*
Y00973*
Y00974*
Y00974*
Y00975*
Y00975*
Y00976*
Y00976*
Y00977*
Y00978*
Y00978*
Y00979*
Y00979*
Y0098*
Y0098*
Y00981*
Y00981*
Y00982*
Y00982*
Y00983*
Y00983*
Y00984*
Y00985*
Y00985*
Y00986*
Y00986*
Y00987*
Y00987*
Y00988*
Y00988*
Y00989*
Y00989*
Y0099*
Y0099*
Y00991*
Y00992*
Y00992*
Y00993*
Y00993*
Y00994*
Y00994*
Y00995*
Y00995*
Y00996*
Y00996*
Y00997*
Y00998*
Y00998*
Y00999*
Y00999*
Y01*
Y01*
Y01001*
Y01001*
Y01002*
Y01002*
Y01003*
Y01003*
Y01004*
Y01005*
Y01005*
Y01006*
Y01006*
Y01007*
Y01007*
Y01008*
Y01008*
Y01009*
Y01009*
Y0101*
Y0101*
Y01011*
Y01012*
Y01012*
Y01013*
Y01013*
Y01014*
Y01014*
Y01015*
Y01015*
Y01016*
X06215*
Y01015*
Y01015*
Y01014*
Y01014*
Y01013*
Y01013*
Y01012*
Y01012*
Y01011*
Y0101*
Y0101*
Y01009*
Y01009*
Y01008*
Y01008*
Y01007*
Y01007*
Y01006*
Y01006*
Y01005*
Y01005*
Y01004*
Y01003*
Y01003*
Y01002*
Y01002*
Y01001*
Y01001*
Y01*
Y01*
Y00999*
Y00999*
Y00998*
Y00998*
Y00997*
Y00996*
Y00996*
Y00995*
Y00995*
Y00994*
Y00994*
Y00993*
Y00993*
Y00992*
Y00992*
Y00991*
Y0099*
Y0099*
Y00989*
Y00989*
Y00988*
Y00988*
Y00987*
Y00987*
Y00986*
Y00986*
Y00985*
Y00985*
Y00984*
Y00983*
Y00983*
Y00982*
Y00982*
Y00981*
Y00981*
Y0098*
Y0098*
Y00979*
Y00979*
Y00978*
Y00978*
Y00977*
Y00976*
Y00976*
Y00975*
Y00975*
Y00974*
Y00974*
Y00973*
Y00973*
Y00972*
Y00972*
Y00971*
Y0097*
Y0097*
Y00969*
Y00969*
Y00968*
Y00968*
Y00967*
Y00967*
Y00966*
Y00966*
Y00965*
Y00965*
Y00964*
Y00963*
Y00963*
Y00962*
Y00962*
Y00961*
Y00961*
Y0096*
Y0096*
Y00959*
Y00959*
Y00958*
Y00958*
Y00957*
Y00956*
Y00956*
Y00955*
Y00955*
Y00954*
Y00954*
Y00953*
Y00953*
Y00952*
Y00952*
Y00951*
Y0095*
Y0095*
Y00949*
Y00949*
Y00948*
Y00948*
Y00947*
Y00947*
Y00946*
Y00946*
Y00945*
Y00945*
Y00944*
Y00943*
Y00943*
Y00942*
Y00942*
Y00941*
Y00941*
Y0094*
Y0094*
Y00939*
Y00939*
Y00938*
Y00938*
Y00937*
Y00936*
Y00936*
Y00935*
Y00935*
Y00934*
Y00934*
Y00933*
Y00933*
Y00932*
Y00932*
Y00931*
Y0093*
Y0093*
Y00929*
X06216*
Y00929*
Y00928*
X06216*
Y00928*
X06217*
Y00927*
X06241*
Y00928*
X06242*
Y00928*
X06242*
Y00929*
X06243*
Y00929*
Y0093*
Y0093*
Y00931*
Y00932*
Y00932*
Y00933*
Y00933*
Y00934*
Y00934*
Y00935*
Y00935*
Y00936*
Y00936*
Y00937*
Y00938*
Y00938*
Y00939*
Y00939*
Y0094*
Y0094*
Y00941*
Y00941*
Y00942*
Y00942*
Y00943*
Y00943*
Y00944*
Y00945*
Y00945*
Y00946*
Y00946*
Y00947*
Y00947*
Y00948*
Y00948*
Y00949*
Y00949*
Y0095*
Y0095*
Y00951*
Y00952*
Y00952*
Y00953*
Y00953*
Y00954*
Y00954*
Y00955*
Y00955*
Y00956*
Y00956*
Y00957*
Y00958*
Y00958*
Y00959*
Y00959*
Y0096*
Y0096*
Y00961*
Y00961*
Y00962*
Y00962*
Y00963*
Y00963*
Y00964*
Y00965*
Y00965*
Y00966*
Y00966*
Y00967*
Y00967*
Y00968*
Y00968*
Y00969*
Y00969*
Y0097*
Y0097*
Y00971*
Y00972*
Y00972*
Y00973*
Y00973*
Y00974*
Y00974*
Y00975*
Y00975*
Y00976*
Y00976*
Y00977*
Y00978*
Y00978*
Y00979*
Y00979*
Y0098*
Y0098*
Y00981*
Y00981*
Y00982*
Y00982*
Y00983*
Y00983*
Y00984*
Y00985*
Y00985*
Y00986*
Y00986*
Y00987*
Y00987*
Y00988*
Y00988*
Y00989*
Y00989*
Y0099*
Y0099*
Y00991*
Y00992*
Y00992*
Y00993*
Y00993*
Y00994*
Y00994*
Y00995*
Y00995*
Y00996*
Y00996*
Y00997*
Y00998*
Y00998*
Y00999*
Y00999*
Y01*
Y01*
Y01001*
Y01001*
Y01002*
Y01002*
Y01003*
Y01003*
Y01004*
Y01005*
Y01005*
Y01006*
Y01006*
Y01007*
Y01007*
Y01008*
Y01008*
Y01009*
Y01009*
Y0101*
Y0101*
Y01011*
Y01012*
Y01012*
Y01013*
Y01013*
Y01014*
Y01014*
Y01015*
Y01015*
Y01016*
X0625*
Y01016*
X06251*
Y01016*
X06252*
Y01016*
Y01017*
Y01018*
Y01018*
Y01019*
Y01019*
Y0102*
Y0102*
Y01021*
Y01021*
Y01022*
Y01022*
Y01023*
Y01023*
Y01024*
Y01025*
Y01025*
Y01026*
Y01026*
Y01027*
Y01027*
Y01028*
Y01028*
Y01029*
Y01029*
Y0103*
Y0103*
Y01031*
Y01032*
Y01032*
Y01033*
Y01033*
Y01034*
Y01034*
Y01035*
Y01035*
Y01036*
Y01036*
Y01037*
Y01038*
Y01038*
Y01039*
Y01039*
Y0104*
Y0104*
Y01041*
Y01041*
Y01042*
Y01042*
Y01043*
Y01043*
Y01044*
Y01045*
Y01045*
G37*
G36*
X06151D02*
X06126D01*
Y01045*
X06125*
Y01044*
Y01043*
X06124*
Y01043*
Y01042*
X06124*
Y01042*
Y01041*
Y01041*
Y0104*
Y0104*
Y01039*
Y01039*
Y01038*
Y01038*
Y01037*
Y01036*
Y01036*
Y01035*
Y01035*
Y01034*
Y01034*
Y01033*
Y01033*
Y01032*
Y01032*
Y01031*
Y0103*
Y0103*
Y01029*
Y01029*
Y01028*
Y01028*
Y01027*
Y01027*
Y01026*
Y01026*
Y01025*
Y01025*
Y01024*
Y01023*
Y01023*
Y01022*
Y01022*
Y01021*
Y01021*
Y0102*
Y0102*
Y01019*
Y01019*
Y01018*
Y01018*
Y01017*
Y01016*
Y01016*
Y01015*
Y01015*
Y01014*
Y01014*
Y01013*
Y01013*
Y01012*
Y01012*
Y01011*
Y0101*
Y0101*
Y01009*
Y01009*
Y01008*
Y01008*
Y01007*
Y01007*
Y01006*
Y01006*
Y01005*
Y01005*
Y01004*
Y01003*
Y01003*
Y01002*
Y01002*
Y01001*
Y01001*
Y01*
Y01*
Y00999*
Y00999*
Y00998*
Y00998*
Y00997*
Y00996*
Y00996*
Y00995*
Y00995*
Y00994*
Y00994*
Y00993*
Y00993*
Y00992*
Y00992*
Y00991*
Y0099*
Y0099*
Y00989*
Y00989*
Y00988*
Y00988*
Y00987*
Y00987*
Y00986*
Y00986*
Y00985*
Y00985*
Y00984*
Y00983*
Y00983*
Y00982*
Y00982*
Y00981*
Y00981*
Y0098*
Y0098*
Y00979*
Y00979*
Y00978*
Y00978*
Y00977*
Y00976*
Y00976*
Y00975*
Y00975*
Y00974*
Y00974*
Y00973*
Y00973*
Y00972*
Y00972*
Y00971*
Y0097*
Y0097*
Y00969*
Y00969*
Y00968*
Y00968*
Y00967*
Y00967*
Y00966*
Y00966*
Y00965*
Y00965*
Y00964*
Y00963*
Y00963*
Y00962*
Y00962*
Y00961*
Y00961*
Y0096*
Y0096*
Y00959*
Y00959*
Y00958*
Y00958*
Y00957*
Y00956*
Y00956*
Y00955*
Y00955*
Y00954*
Y00954*
Y00953*
Y00953*
Y00952*
Y00952*
Y00951*
Y0095*
Y0095*
Y00949*
Y00949*
Y00948*
Y00948*
Y00947*
Y00947*
Y00946*
Y00946*
Y00945*
Y00945*
Y00944*
Y00943*
Y00943*
Y00942*
Y00942*
Y00941*
Y00941*
Y0094*
Y0094*
Y00939*
Y00939*
Y00938*
Y00938*
Y00937*
Y00936*
Y00936*
Y00935*
Y00935*
Y00934*
Y00934*
Y00933*
Y00933*
Y00932*
Y00932*
Y00931*
Y0093*
Y0093*
Y00929*
X06124*
Y00929*
Y00928*
X06125*
Y00928*
X06125*
Y00927*
X06152*
Y00928*
X06153*
Y00928*
X06153*
Y00929*
Y00929*
Y0093*
Y0093*
Y00931*
Y00932*
Y00932*
Y00933*
Y00933*
Y00934*
Y00934*
Y00935*
Y00935*
Y00936*
Y00936*
Y00937*
Y00938*
Y00938*
Y00939*
Y00939*
Y0094*
Y0094*
Y00941*
Y00941*
Y00942*
Y00942*
Y00943*
Y00943*
Y00944*
Y00945*
Y00945*
Y00946*
Y00946*
Y00947*
Y00947*
Y00948*
Y00948*
Y00949*
Y00949*
Y0095*
Y0095*
Y00951*
Y00952*
Y00952*
Y00953*
Y00953*
Y00954*
Y00954*
Y00955*
Y00955*
Y00956*
Y00956*
Y00957*
Y00958*
Y00958*
Y00959*
Y00959*
Y0096*
Y0096*
Y00961*
Y00961*
Y00962*
Y00962*
Y00963*
Y00963*
Y00964*
Y00965*
Y00965*
Y00966*
Y00966*
Y00967*
Y00967*
Y00968*
Y00968*
Y00969*
Y00969*
Y0097*
Y0097*
Y00971*
Y00972*
Y00972*
Y00973*
Y00973*
Y00974*
Y00974*
Y00975*
Y00975*
Y00976*
Y00976*
Y00977*
Y00978*
Y00978*
Y00979*
Y00979*
Y0098*
Y0098*
Y00981*
Y00981*
Y00982*
Y00982*
Y00983*
Y00983*
Y00984*
Y00985*
Y00985*
Y00986*
Y00986*
Y00987*
Y00987*
Y00988*
Y00988*
Y00989*
Y00989*
Y0099*
Y0099*
Y00991*
Y00992*
Y00992*
Y00993*
Y00993*
Y00994*
Y00994*
Y00995*
Y00995*
Y00996*
Y00996*
Y00997*
Y00998*
Y00998*
Y00999*
Y00999*
Y01*
Y01*
Y01001*
Y01001*
Y01002*
Y01002*
Y01003*
Y01003*
Y01004*
Y01005*
Y01005*
Y01006*
Y01006*
Y01007*
Y01007*
Y01008*
Y01008*
Y01009*
Y01009*
Y0101*
Y0101*
Y01011*
Y01012*
Y01012*
Y01013*
Y01013*
Y01014*
Y01014*
Y01015*
Y01015*
Y01016*
Y01016*
Y01017*
Y01018*
Y01018*
Y01019*
Y01019*
Y0102*
Y0102*
Y01021*
Y01021*
Y01022*
Y01022*
Y01023*
Y01023*
Y01024*
Y01025*
Y01025*
Y01026*
Y01026*
Y01027*
Y01027*
Y01028*
Y01028*
Y01029*
Y01029*
Y0103*
Y0103*
Y01031*
Y01032*
Y01032*
Y01033*
Y01033*
Y01034*
Y01034*
Y01035*
Y01035*
Y01036*
Y01036*
Y01037*
Y01038*
Y01038*
Y01039*
Y01039*
Y0104*
Y0104*
Y01041*
Y01041*
Y01042*
Y01042*
Y01043*
Y01043*
X06153*
Y01044*
X06152*
Y01045*
X06151*
Y01045*
G37*
G36*
X0629Y01132D02*
X0627D01*
Y01132*
X06262*
Y01131*
X06256*
Y01131*
X06252*
Y0113*
X06249*
Y01129*
X06245*
Y01129*
X06242*
Y01128*
X06239*
Y01128*
X06236*
Y01127*
X06233*
Y01127*
X06231*
Y01126*
X06229*
Y01126*
X06227*
Y01125*
X06225*
Y01125*
X06223*
Y01124*
X06221*
Y01123*
X06219*
Y01123*
X06218*
Y01122*
X06216*
Y01122*
X06214*
Y01121*
X06212*
Y01121*
X06211*
Y0112*
X0621*
Y0112*
X06208*
Y01119*
X06206*
Y01119*
X06205*
Y01118*
X06204*
Y01118*
X06202*
Y01117*
X06201*
Y01116*
X06199*
Y01116*
X06198*
Y01115*
X06197*
Y01115*
X06196*
Y01114*
X06195*
Y01114*
X06193*
Y01113*
X06192*
Y01113*
X06191*
Y01112*
X0619*
Y01112*
X06189*
Y01111*
X06188*
Y01111*
X06186*
Y0111*
X06185*
Y01109*
X06184*
Y01109*
X06183*
Y01108*
X06182*
Y01108*
X06181*
Y01107*
X06181*
Y01107*
X06179*
Y01106*
X06178*
Y01106*
X06177*
Y01105*
X06176*
Y01105*
X06176*
Y01104*
X06175*
Y01103*
X06173*
Y01103*
X06173*
Y01102*
X06172*
Y01102*
X06171*
Y01101*
X0617*
Y01101*
X06169*
Y011*
X06168*
Y011*
X06168*
Y01099*
X06166*
Y01099*
X06166*
Y01098*
X06165*
Y01098*
X06164*
Y01097*
X06163*
Y01096*
X06163*
Y01096*
X06162*
Y01095*
X06161*
Y01095*
X0616*
Y01094*
X06159*
Y01094*
X06159*
Y01093*
X06158*
Y01093*
X06157*
Y01092*
X06156*
Y01092*
X06156*
Y01091*
X06155*
Y01091*
X06154*
Y0109*
X06153*
Y01089*
X06153*
Y01089*
X06152*
Y01088*
X06151*
Y01088*
X06151*
Y01087*
X0615*
Y01087*
X06149*
Y01086*
X06149*
Y01086*
X06148*
Y01085*
X06148*
Y01085*
X06146*
Y01084*
X06146*
Y01083*
X06145*
Y01083*
X06145*
Y01082*
X06144*
Y01082*
X06143*
Y01081*
X06143*
Y01081*
X06142*
Y0108*
X06142*
Y0108*
X06141*
Y01079*
X06141*
Y01079*
X0614*
Y01078*
X06139*
Y01078*
X06138*
Y01077*
X06138*
Y01076*
X06137*
Y01076*
X06137*
Y01075*
X06136*
Y01075*
X06136*
Y01074*
X06135*
Y01074*
X06135*
Y01073*
X06134*
Y01073*
X06133*
Y01072*
X06133*
Y01072*
X06132*
Y01071*
X06132*
Y0107*
X06131*
Y0107*
X06131*
Y01069*
X0613*
Y01069*
X0613*
Y01068*
X06129*
Y01068*
X06129*
Y01067*
X06128*
Y01067*
X06128*
Y01066*
X06127*
Y01066*
X06126*
Y01065*
X06126*
Y01065*
X06125*
Y01064*
Y01063*
X06125*
Y01063*
X06124*
Y01062*
X06124*
Y01062*
X06123*
Y01061*
X06123*
Y01061*
X06122*
Y0106*
X06122*
Y0106*
X06121*
Y01059*
Y01059*
X06121*
Y01058*
X0612*
Y01058*
X06119*
Y01057*
X06119*
Y01056*
X06118*
Y01056*
Y01055*
X06118*
Y01055*
X06117*
Y01054*
X06117*
Y01054*
X06125*
Y01054*
X06126*
Y01055*
X06126*
Y01055*
Y01056*
X06127*
Y01056*
X06128*
Y01057*
X06128*
Y01058*
X06129*
Y01058*
X06129*
Y01059*
X0613*
Y01059*
X0613*
Y0106*
X06131*
Y0106*
Y01061*
X06131*
Y01061*
X06132*
Y01062*
X06132*
Y01062*
X06133*
Y01063*
X06133*
Y01063*
X06134*
Y01064*
X06135*
Y01065*
X06135*
Y01065*
X06136*
Y01066*
X06136*
Y01066*
X06137*
Y01067*
X06137*
Y01067*
X06138*
Y01068*
X06138*
Y01068*
X06139*
Y01069*
X06139*
Y01069*
X0614*
Y0107*
X06141*
Y0107*
X06141*
Y01071*
X06142*
Y01072*
X06143*
Y01072*
X06143*
Y01073*
X06144*
Y01073*
X06144*
Y01074*
X06145*
Y01074*
X06145*
Y01075*
X06146*
Y01075*
X06146*
Y01076*
X06147*
Y01076*
X06148*
Y01077*
X06149*
Y01078*
X06149*
Y01078*
X0615*
Y01079*
X0615*
Y01079*
X06151*
Y0108*
X06152*
Y0108*
X06152*
Y01081*
X06153*
Y01081*
X06154*
Y01082*
X06155*
Y01082*
X06155*
Y01083*
X06156*
Y01083*
X06157*
Y01084*
X06157*
Y01085*
X06158*
Y01085*
X06159*
Y01086*
X06159*
Y01086*
X0616*
Y01087*
X06161*
Y01087*
X06162*
Y01088*
X06162*
Y01088*
X06163*
Y01089*
X06164*
Y01089*
X06165*
Y0109*
X06165*
Y01091*
X06166*
Y01091*
X06167*
Y01092*
X06168*
Y01092*
X06169*
Y01093*
X0617*
Y01093*
X0617*
Y01094*
X06171*
Y01094*
X06172*
Y01095*
X06173*
Y01095*
X06174*
Y01096*
X06175*
Y01096*
X06176*
Y01097*
X06177*
Y01098*
X06177*
Y01098*
X06178*
Y01099*
X06179*
Y01099*
X0618*
Y011*
X06181*
Y011*
X06182*
Y01101*
X06183*
Y01101*
X06184*
Y01102*
X06185*
Y01102*
X06186*
Y01103*
X06187*
Y01103*
X06188*
Y01104*
X06189*
Y01105*
X0619*
Y01105*
X06191*
Y01106*
X06193*
Y01106*
X06194*
Y01107*
X06195*
Y01107*
X06196*
Y01108*
X06197*
Y01108*
X06198*
Y01109*
X062*
Y01109*
X06201*
Y0111*
X06202*
Y01111*
X06204*
Y01111*
X06205*
Y01112*
X06206*
Y01112*
X06208*
Y01113*
X06209*
Y01113*
X06211*
Y01114*
X06212*
Y01114*
X06214*
Y01115*
X06215*
Y01115*
X06217*
Y01116*
X06219*
Y01116*
X06221*
Y01117*
X06222*
Y01118*
X06224*
Y01118*
X06226*
Y01119*
X06228*
Y01119*
X0623*
Y0112*
X06232*
Y0112*
X06235*
Y01121*
X06237*
Y01121*
X0624*
Y01122*
X06242*
Y01122*
X06246*
Y01123*
X06249*
Y01123*
X06253*
Y01124*
X06257*
Y01125*
X06263*
Y01125*
X06273*
Y01126*
X06286*
Y01125*
X06287*
Y01126*
X06288*
Y01125*
X06296*
Y01125*
X06302*
Y01124*
X06307*
Y01123*
X0631*
Y01123*
X06314*
Y01122*
X06317*
Y01122*
X06319*
Y01121*
X06322*
Y01121*
X06325*
Y0112*
X06327*
Y0112*
X06329*
Y01119*
X06331*
Y01119*
X06334*
Y01118*
X06335*
Y01118*
X06337*
Y01117*
X06339*
Y01116*
X06341*
Y01116*
X06342*
Y01115*
X06344*
Y01115*
X06345*
Y01114*
X06347*
Y01114*
X06349*
Y01113*
X0635*
Y01113*
X06351*
Y01112*
X06353*
Y01112*
X06354*
Y01111*
X06356*
Y01111*
X06357*
Y0111*
X06358*
Y01109*
X06359*
Y01109*
X06361*
Y01108*
X06362*
Y01108*
X06363*
Y01107*
X06364*
Y01107*
X06365*
Y01106*
X06366*
Y01106*
X06368*
Y01105*
X06369*
Y01105*
X0637*
Y01104*
X06371*
Y01103*
X06372*
Y01103*
X06373*
Y01102*
X06374*
Y01102*
X06375*
Y01101*
X06376*
Y01101*
X06377*
Y011*
X06378*
Y011*
X06379*
Y01099*
X0638*
Y01099*
X06381*
Y01098*
X06382*
Y01098*
X06383*
Y01097*
X06384*
Y01096*
X06385*
Y01096*
X06385*
Y01095*
X06386*
Y01095*
X06388*
Y01094*
X06388*
Y01094*
X06389*
Y01093*
X0639*
Y01093*
X06391*
Y01092*
X06391*
Y01092*
X06392*
Y01091*
X06393*
Y01091*
X06394*
Y0109*
X06395*
Y01089*
X06396*
Y01089*
X06396*
Y01088*
X06397*
Y01088*
X06398*
Y01087*
X06398*
Y01087*
X06399*
Y01086*
X064*
Y01086*
X06401*
Y01085*
X06402*
Y01085*
X06402*
Y01084*
X06403*
Y01083*
X06404*
Y01083*
X06404*
Y01082*
X06405*
Y01082*
X06405*
Y01081*
X06406*
Y01081*
X06407*
Y0108*
X06408*
Y0108*
X06408*
Y01079*
X06409*
Y01079*
X0641*
Y01078*
X0641*
Y01078*
X06411*
Y01077*
X06411*
Y01076*
X06412*
Y01076*
X06413*
Y01075*
X06414*
Y01075*
X06414*
Y01074*
X06415*
Y01074*
X06415*
Y01073*
X06416*
Y01073*
X06416*
Y01072*
X06417*
Y01072*
X06417*
Y01071*
X06418*
Y0107*
X06419*
Y0107*
X06419*
Y01069*
X0642*
Y01069*
X06421*
Y01068*
X06421*
Y01068*
X06422*
Y01067*
X06422*
Y01067*
X06423*
Y01066*
X06423*
Y01066*
X06424*
Y01065*
X06424*
Y01065*
X06425*
Y01064*
X06425*
Y01063*
X06426*
Y01063*
X06427*
Y01062*
X06427*
Y01062*
X06428*
Y01061*
Y01061*
X06428*
Y0106*
X06429*
Y0106*
X06429*
Y01059*
X0643*
Y01059*
X0643*
Y01058*
X06431*
Y01058*
X06431*
Y01057*
X06432*
Y01056*
X06432*
Y01056*
Y01055*
X06433*
Y01055*
X06434*
Y01054*
X06434*
Y01054*
X06435*
Y01053*
X06435*
Y01053*
X06436*
Y01052*
Y01052*
X06436*
Y01051*
X06437*
Y0105*
X06437*
Y0105*
X06438*
Y01049*
Y01049*
X06438*
Y01048*
X06439*
Y01048*
X06439*
Y01047*
X0644*
Y01047*
Y01046*
X06441*
Y01046*
X06441*
Y01045*
X06442*
Y01045*
Y01044*
X06442*
Y01043*
X06443*
Y01043*
X06443*
Y01042*
Y01042*
X06444*
Y01041*
X06444*
Y01041*
Y0104*
X06445*
Y0104*
X06445*
Y01039*
X06446*
Y01039*
Y01038*
X06447*
Y01038*
X06447*
Y01037*
Y01036*
X06448*
Y01036*
X06448*
Y01035*
Y01035*
X06449*
Y01034*
X06449*
Y01034*
Y01033*
X0645*
Y01033*
X0645*
Y01032*
Y01032*
X06451*
Y01031*
X06451*
Y0103*
Y0103*
X06452*
Y01029*
Y01029*
X06452*
Y01028*
X06453*
Y01028*
Y01027*
X06454*
Y01027*
Y01026*
X06454*
Y01026*
X06455*
Y01025*
Y01025*
X06455*
Y01024*
Y01023*
X06456*
Y01023*
Y01022*
X06456*
Y01022*
X06457*
Y01021*
Y01021*
X06457*
Y0102*
Y0102*
X06458*
Y01019*
Y01019*
X06458*
Y01018*
Y01018*
X06459*
Y01017*
Y01016*
X06459*
Y01016*
X0646*
Y01015*
Y01015*
X06461*
Y01014*
Y01014*
X06461*
Y01013*
Y01013*
X06462*
Y01012*
Y01012*
X06462*
Y01011*
Y0101*
Y0101*
X06463*
Y01009*
Y01009*
X06463*
Y01008*
Y01008*
X06464*
Y01007*
Y01007*
X06464*
Y01006*
Y01006*
X06465*
Y01005*
Y01005*
X06465*
Y01004*
Y01003*
Y01003*
X06466*
Y01002*
Y01002*
X06467*
Y01001*
Y01001*
X06467*
Y01*
Y01*
Y00999*
X06468*
Y00999*
Y00998*
X06468*
Y00998*
Y00997*
Y00996*
X06469*
Y00996*
Y00995*
X06469*
Y00995*
Y00994*
Y00994*
X0647*
Y00993*
Y00993*
Y00992*
X0647*
Y00992*
Y00991*
Y0099*
X06471*
Y0099*
Y00989*
X06471*
Y00989*
Y00988*
Y00988*
X06472*
Y00987*
Y00987*
Y00986*
X06472*
Y00986*
Y00985*
Y00985*
Y00984*
X06473*
Y00983*
Y00983*
Y00982*
X06474*
Y00982*
Y00981*
Y00981*
X06474*
Y0098*
Y0098*
Y00979*
Y00979*
X06475*
Y00978*
Y00978*
Y00977*
X06475*
Y00976*
Y00976*
Y00975*
Y00975*
X06476*
Y00974*
Y00974*
Y00973*
Y00973*
X06476*
Y00972*
Y00972*
Y00971*
Y0097*
X06477*
Y0097*
Y00969*
Y00969*
Y00968*
X06477*
Y00968*
Y00967*
Y00967*
Y00966*
Y00966*
X06478*
Y00965*
Y00965*
Y00964*
Y00963*
X06478*
Y00963*
Y00962*
Y00962*
Y00961*
Y00961*
Y0096*
X06479*
Y0096*
Y00959*
Y00959*
Y00958*
Y00958*
X06479*
Y00957*
Y00956*
Y00956*
Y00955*
Y00955*
Y00954*
X0648*
Y00954*
Y00953*
Y00953*
Y00952*
Y00952*
Y00951*
Y0095*
X06481*
Y0095*
Y00949*
Y00949*
Y00948*
Y00948*
Y00947*
Y00947*
Y00946*
Y00946*
X06481*
Y00945*
Y00945*
Y00944*
Y00943*
Y00943*
Y00942*
Y00942*
Y00941*
Y00941*
X06482*
Y0094*
Y0094*
Y00939*
Y00939*
Y00938*
Y00938*
Y00937*
Y00936*
Y00936*
Y00935*
Y00935*
Y00934*
Y00934*
Y00933*
Y00933*
Y00932*
Y00932*
X06482*
Y00931*
Y0093*
Y0093*
Y00929*
Y00929*
Y00928*
Y00928*
Y00927*
Y00927*
Y00926*
Y00926*
X06489*
Y00926*
Y00927*
Y00927*
Y00928*
Y00928*
Y00929*
Y00929*
Y0093*
Y0093*
Y00931*
Y00932*
Y00932*
X06488*
Y00933*
X06489*
Y00933*
Y00934*
Y00934*
X06488*
Y00935*
Y00935*
Y00936*
Y00936*
Y00937*
Y00938*
Y00938*
Y00939*
Y00939*
Y0094*
Y0094*
Y00941*
Y00941*
Y00942*
X06488*
Y00942*
Y00943*
Y00943*
Y00944*
Y00945*
Y00945*
Y00946*
Y00946*
Y00947*
Y00947*
X06487*
Y00948*
Y00948*
Y00949*
Y00949*
Y0095*
Y0095*
Y00951*
Y00952*
X06487*
Y00952*
Y00953*
Y00953*
Y00954*
Y00954*
Y00955*
Y00955*
X06486*
Y00956*
Y00956*
Y00957*
Y00958*
Y00958*
Y00959*
X06485*
Y00959*
Y0096*
Y0096*
Y00961*
Y00961*
X06485*
Y00962*
Y00962*
Y00963*
Y00963*
Y00964*
X06484*
Y00965*
Y00965*
Y00966*
Y00966*
Y00967*
X06484*
Y00967*
Y00968*
Y00968*
Y00969*
Y00969*
X06483*
Y0097*
Y0097*
Y00971*
Y00972*
X06483*
Y00972*
Y00973*
Y00973*
Y00974*
X06482*
Y00974*
Y00975*
Y00975*
Y00976*
X06482*
Y00976*
Y00977*
Y00978*
Y00978*
X06481*
Y00979*
Y00979*
Y0098*
X06481*
Y0098*
Y00981*
Y00981*
Y00982*
X0648*
Y00982*
Y00983*
Y00983*
X06479*
Y00984*
Y00985*
Y00985*
Y00986*
X06479*
Y00986*
Y00987*
Y00987*
X06478*
Y00988*
Y00988*
Y00989*
X06478*
Y00989*
Y0099*
Y0099*
X06477*
Y00991*
Y00992*
Y00992*
X06477*
Y00993*
Y00993*
Y00994*
X06476*
Y00994*
Y00995*
X06476*
Y00995*
Y00996*
Y00996*
X06475*
Y00997*
Y00998*
Y00998*
X06475*
Y00999*
Y00999*
X06474*
Y01*
Y01*
Y01001*
X06474*
Y01001*
Y01002*
X06473*
Y01002*
Y01003*
Y01003*
X06472*
Y01004*
Y01005*
X06472*
Y01005*
Y01006*
X06471*
Y01006*
Y01007*
Y01007*
X06471*
Y01008*
Y01008*
X0647*
Y01009*
Y01009*
X0647*
Y0101*
Y0101*
X06469*
Y01011*
Y01012*
Y01012*
X06469*
Y01013*
Y01013*
X06468*
Y01014*
Y01014*
X06468*
Y01015*
Y01015*
X06467*
Y01016*
Y01016*
X06467*
Y01017*
Y01018*
X06466*
Y01018*
Y01019*
X06465*
Y01019*
Y0102*
X06465*
Y0102*
Y01021*
X06464*
Y01021*
Y01022*
X06464*
Y01022*
X06463*
Y01023*
Y01023*
X06463*
Y01024*
Y01025*
X06462*
Y01025*
Y01026*
X06462*
Y01026*
Y01027*
X06461*
Y01027*
X06461*
Y01028*
Y01028*
X0646*
Y01029*
Y01029*
X06459*
Y0103*
X06459*
Y0103*
Y01031*
X06458*
Y01032*
Y01032*
X06458*
Y01033*
X06457*
Y01033*
Y01034*
X06457*
Y01034*
Y01035*
X06456*
Y01035*
X06456*
Y01036*
Y01036*
X06455*
Y01037*
X06455*
Y01038*
Y01038*
X06454*
Y01039*
X06454*
Y01039*
Y0104*
X06453*
Y0104*
X06452*
Y01041*
Y01041*
X06452*
Y01042*
X06451*
Y01042*
Y01043*
X06451*
Y01043*
X0645*
Y01044*
X0645*
Y01045*
Y01045*
X06449*
Y01046*
X06449*
Y01046*
Y01047*
X06448*
Y01047*
X06448*
Y01048*
X06447*
Y01048*
Y01049*
X06447*
Y01049*
X06446*
Y0105*
X06445*
Y0105*
X06445*
Y01051*
Y01052*
X06444*
Y01052*
X06444*
Y01053*
X06443*
Y01053*
Y01054*
X06443*
Y01054*
X06442*
Y01055*
X06442*
Y01055*
X06441*
Y01056*
X06441*
Y01056*
Y01057*
X0644*
Y01058*
X06439*
Y01058*
X06439*
Y01059*
X06438*
Y01059*
X06438*
Y0106*
Y0106*
X06437*
Y01061*
X06437*
Y01061*
X06436*
Y01062*
X06436*
Y01062*
X06435*
Y01063*
X06435*
Y01063*
X06434*
Y01064*
X06434*
Y01065*
Y01065*
X06433*
Y01066*
X06432*
Y01066*
X06432*
Y01067*
X06431*
Y01067*
X06431*
Y01068*
X0643*
Y01068*
X0643*
Y01069*
X06429*
Y01069*
X06429*
Y0107*
X06428*
Y0107*
X06428*
Y01071*
X06427*
Y01072*
X06427*
Y01072*
X06426*
Y01073*
X06425*
Y01073*
X06425*
Y01074*
X06424*
Y01074*
X06424*
Y01075*
X06423*
Y01075*
X06423*
Y01076*
X06422*
Y01076*
X06421*
Y01077*
X06421*
Y01078*
X0642*
Y01078*
X06419*
Y01079*
X06419*
Y01079*
X06418*
Y0108*
X06418*
Y0108*
X06417*
Y01081*
X06417*
Y01081*
X06416*
Y01082*
X06415*
Y01082*
X06415*
Y01083*
X06414*
Y01083*
X06414*
Y01084*
X06412*
Y01085*
X06412*
Y01085*
X06411*
Y01086*
X06411*
Y01086*
X0641*
Y01087*
X06409*
Y01087*
X06409*
Y01088*
X06408*
Y01088*
X06407*
Y01089*
X06406*
Y01089*
X06406*
Y0109*
X06405*
Y01091*
X06404*
Y01091*
X06404*
Y01092*
X06403*
Y01092*
X06402*
Y01093*
X06402*
Y01093*
X06401*
Y01094*
X064*
Y01094*
X06399*
Y01095*
X06398*
Y01095*
X06398*
Y01096*
X06397*
Y01096*
X06396*
Y01097*
X06395*
Y01098*
X06395*
Y01098*
X06394*
Y01099*
X06393*
Y01099*
X06392*
Y011*
X06391*
Y011*
X0639*
Y01101*
X06389*
Y01101*
X06389*
Y01102*
X06388*
Y01102*
X06386*
Y01103*
X06386*
Y01103*
X06385*
Y01104*
X06384*
Y01105*
X06383*
Y01105*
X06382*
Y01106*
X06381*
Y01106*
X0638*
Y01107*
X06379*
Y01107*
X06378*
Y01108*
X06377*
Y01108*
X06376*
Y01109*
X06375*
Y01109*
X06374*
Y0111*
X06372*
Y01111*
X06371*
Y01111*
X06371*
Y01112*
X0637*
Y01112*
X06368*
Y01113*
X06367*
Y01113*
X06366*
Y01114*
X06365*
Y01114*
X06364*
Y01115*
X06362*
Y01115*
X06361*
Y01116*
X0636*
Y01116*
X06358*
Y01117*
X06357*
Y01118*
X06356*
Y01118*
X06354*
Y01119*
X06353*
Y01119*
X06351*
Y0112*
X0635*
Y0112*
X06348*
Y01121*
X06347*
Y01121*
X06345*
Y01122*
X06344*
Y01122*
X06342*
Y01123*
X0634*
Y01123*
X06338*
Y01124*
X06336*
Y01125*
X06335*
Y01125*
X06332*
Y01126*
X0633*
Y01126*
X06328*
Y01127*
X06326*
Y01127*
X06323*
Y01128*
X06321*
Y01128*
X06318*
Y01129*
X06315*
Y01129*
X06311*
Y0113*
X06307*
Y01131*
X06303*
Y01131*
X06298*
Y01132*
X0629*
Y01132*
G37*
G36*
X06214Y00918D02*
X06213D01*
Y00917*
X06212*
Y00918*
X06148*
Y00917*
X06146*
Y00916*
X06144*
Y00916*
X06143*
Y00915*
X06143*
Y00915*
X06142*
Y00914*
X06142*
Y00914*
X06141*
Y00913*
X06141*
Y00913*
X0614*
Y00912*
X06139*
Y00912*
X06139*
Y00911*
X06138*
Y0091*
X06138*
Y0091*
X06137*
Y00909*
X06137*
Y00909*
X06136*
Y00908*
X06136*
Y00908*
X06135*
Y00907*
X06135*
Y00907*
X06134*
Y00906*
X06133*
Y00906*
X06133*
Y00905*
X06132*
Y00905*
X06132*
Y00904*
X06131*
Y00903*
X06131*
Y00903*
X0613*
Y00902*
X0613*
Y00902*
X06129*
Y00901*
X06129*
Y00901*
X06128*
Y009*
Y009*
X06128*
Y00899*
Y00899*
Y00898*
Y00897*
X06127*
Y00897*
Y00896*
Y00896*
Y00895*
Y00895*
Y00894*
Y00894*
Y00893*
Y00893*
Y00892*
Y00892*
Y00891*
Y0089*
Y0089*
Y00889*
Y00889*
Y00888*
Y00888*
Y00887*
Y00887*
Y00886*
Y00886*
Y00885*
Y00885*
Y00884*
Y00883*
Y00883*
Y00882*
Y00882*
Y00881*
Y00881*
Y0088*
Y0088*
Y00879*
Y00879*
Y00878*
Y00877*
Y00877*
Y00876*
Y00876*
Y00875*
Y00875*
Y00874*
Y00874*
Y00873*
Y00873*
Y00872*
Y00872*
Y00871*
Y0087*
Y0087*
Y00869*
Y00869*
Y00868*
Y00868*
Y00867*
Y00867*
Y00866*
Y00866*
Y00865*
Y00865*
Y00864*
Y00863*
Y00863*
Y00862*
Y00862*
Y00861*
Y00861*
Y0086*
Y0086*
Y00859*
Y00859*
Y00858*
Y00857*
Y00857*
Y00856*
Y00856*
Y00855*
Y00855*
Y00854*
Y00854*
Y00853*
Y00853*
Y00852*
Y00852*
Y00851*
Y0085*
Y0085*
Y00849*
Y00849*
Y00848*
Y00848*
Y00847*
Y00847*
Y00846*
Y00846*
Y00845*
Y00845*
Y00844*
Y00843*
Y00843*
Y00842*
Y00842*
Y00841*
Y00841*
Y0084*
Y0084*
Y00839*
Y00839*
Y00838*
Y00837*
Y00837*
Y00836*
Y00836*
Y00835*
Y00835*
Y00834*
Y00834*
Y00833*
Y00833*
Y00832*
Y00832*
Y00831*
Y0083*
Y0083*
Y00829*
Y00829*
Y00828*
Y00828*
Y00827*
Y00827*
Y00826*
Y00826*
Y00825*
Y00825*
Y00824*
Y00823*
Y00823*
Y00822*
Y00822*
Y00821*
Y00821*
Y0082*
Y0082*
Y00819*
X06128*
Y00819*
Y00818*
Y00817*
X06128*
Y00817*
Y00816*
X06129*
Y00816*
X06129*
Y00815*
X0613*
Y00815*
X0613*
Y00814*
X06131*
Y00814*
X06131*
Y00813*
X06132*
Y00813*
X06132*
Y00812*
X06133*
Y00812*
X06133*
Y00811*
X06134*
Y0081*
X06135*
Y0081*
X06135*
Y00809*
X06136*
Y00809*
X06136*
Y00808*
X06137*
Y00808*
X06137*
Y00807*
X06138*
Y00807*
X06138*
Y00806*
X06139*
Y00806*
X06139*
Y00805*
X0614*
Y00805*
X06141*
Y00804*
X06141*
Y00803*
X06142*
Y00803*
X06142*
Y00802*
X06143*
Y00802*
X06143*
Y00801*
X06144*
Y00801*
X06145*
Y008*
X06146*
Y008*
X06215*
Y008*
X06216*
Y00801*
X06216*
Y00801*
X06217*
Y00802*
Y00802*
Y00803*
Y00803*
Y00804*
Y00805*
Y00805*
Y00806*
Y00806*
Y00807*
Y00807*
Y00808*
Y00808*
Y00809*
Y00809*
Y0081*
Y0081*
Y00811*
Y00812*
Y00812*
Y00813*
Y00813*
Y00814*
Y00814*
Y00815*
Y00815*
Y00816*
Y00816*
Y00817*
Y00817*
Y00818*
Y00819*
Y00819*
Y0082*
Y0082*
Y00821*
Y00821*
Y00822*
Y00822*
Y00823*
Y00823*
Y00824*
Y00825*
Y00825*
Y00826*
Y00826*
Y00827*
X06216*
Y00827*
X06216*
Y00828*
X06215*
Y00828*
X06158*
Y00829*
X06157*
Y00829*
Y0083*
X06157*
Y0083*
Y00831*
Y00832*
Y00832*
Y00833*
Y00833*
Y00834*
Y00834*
Y00835*
Y00835*
Y00836*
Y00836*
Y00837*
Y00837*
Y00838*
Y00839*
Y00839*
Y0084*
Y0084*
Y00841*
Y00841*
Y00842*
Y00842*
Y00843*
Y00843*
Y00844*
Y00845*
Y00845*
Y00846*
Y00846*
Y00847*
Y00847*
Y00848*
Y00848*
Y00849*
Y00849*
Y0085*
Y0085*
Y00851*
Y00852*
Y00852*
Y00853*
Y00853*
Y00854*
Y00854*
Y00855*
Y00855*
Y00856*
Y00856*
Y00857*
Y00857*
Y00858*
Y00859*
Y00859*
Y0086*
Y0086*
Y00861*
Y00861*
Y00862*
Y00862*
Y00863*
Y00863*
Y00864*
Y00865*
Y00865*
Y00866*
Y00866*
Y00867*
Y00867*
Y00868*
Y00868*
Y00869*
Y00869*
Y0087*
Y0087*
Y00871*
Y00872*
Y00872*
Y00873*
Y00873*
Y00874*
Y00874*
Y00875*
Y00875*
Y00876*
Y00876*
Y00877*
Y00877*
Y00878*
Y00879*
Y00879*
Y0088*
Y0088*
Y00881*
Y00881*
Y00882*
Y00882*
Y00883*
Y00883*
Y00884*
Y00885*
Y00885*
Y00886*
Y00886*
Y00887*
Y00887*
X06157*
Y00888*
X06158*
Y00888*
X06211*
Y00889*
X06212*
Y00888*
X06214*
Y00889*
X06216*
Y00889*
X06216*
Y0089*
X06217*
Y0089*
Y00891*
Y00892*
Y00892*
Y00893*
Y00893*
Y00894*
Y00894*
Y00895*
Y00895*
Y00896*
Y00896*
Y00897*
Y00897*
Y00898*
Y00899*
Y00899*
Y009*
Y009*
Y00901*
Y00901*
Y00902*
Y00902*
Y00903*
Y00903*
Y00904*
Y00905*
Y00905*
Y00906*
Y00906*
Y00907*
Y00907*
Y00908*
Y00908*
Y00909*
Y00909*
Y0091*
Y0091*
Y00911*
Y00912*
Y00912*
Y00913*
Y00913*
Y00914*
Y00914*
Y00915*
Y00915*
Y00916*
X06216*
Y00916*
X06216*
Y00917*
X06214*
Y00918*
G37*
G36*
X06309D02*
X06301D01*
Y00917*
X06301*
Y00916*
X063*
Y00916*
X06299*
Y00915*
X06299*
Y00915*
X06298*
Y00914*
X06298*
Y00914*
X06297*
Y00913*
X06297*
Y00913*
X06296*
Y00912*
X06296*
Y00912*
X06295*
Y00911*
X06295*
Y0091*
X06294*
Y0091*
X06294*
Y00909*
X06293*
Y00909*
X06292*
Y00908*
X06292*
Y00908*
X06291*
Y00907*
X06291*
Y00907*
X0629*
Y00906*
X0629*
Y00906*
X06289*
Y00905*
X06289*
Y00905*
X06288*
Y00904*
X06288*
Y00903*
X06287*
Y00903*
X06286*
Y00902*
X06286*
Y00902*
X06285*
Y00901*
X06285*
Y00901*
X06284*
Y009*
X06284*
Y009*
X06283*
Y00899*
X06283*
Y00899*
X06282*
Y00898*
X06282*
Y00897*
X06281*
Y00897*
X06281*
Y00896*
X0628*
Y00896*
X06279*
Y00895*
X06279*
Y00895*
X06278*
Y00894*
X06278*
Y00894*
X06277*
Y00893*
X06277*
Y00893*
X06276*
Y00892*
X06276*
Y00892*
X06275*
Y00891*
X06299*
Y0089*
Y0089*
Y00889*
Y00889*
Y00888*
Y00888*
Y00887*
Y00887*
Y00886*
Y00886*
Y00885*
Y00885*
Y00884*
Y00883*
Y00883*
Y00882*
Y00882*
Y00881*
Y00881*
Y0088*
Y0088*
Y00879*
Y00879*
Y00878*
Y00877*
Y00877*
Y00876*
Y00876*
Y00875*
Y00875*
Y00874*
Y00874*
Y00873*
Y00873*
Y00872*
Y00872*
Y00871*
Y0087*
Y0087*
Y00869*
Y00869*
Y00868*
Y00868*
Y00867*
Y00867*
Y00866*
Y00866*
Y00865*
Y00865*
Y00864*
Y00863*
Y00863*
Y00862*
Y00862*
Y00861*
X0626*
Y00862*
Y00862*
Y00863*
Y00863*
Y00864*
Y00865*
Y00865*
Y00866*
Y00866*
Y00867*
Y00867*
Y00868*
Y00868*
Y00869*
Y00869*
Y0087*
Y0087*
Y00871*
Y00872*
Y00872*
Y00873*
Y00873*
X06259*
Y00873*
X06259*
Y00872*
X06258*
Y00872*
X06258*
Y00871*
X06257*
Y0087*
X06257*
Y0087*
X06256*
Y00869*
X06256*
Y00869*
X06255*
Y00868*
X06255*
Y00868*
X06254*
Y00867*
X06254*
Y00867*
X06253*
Y00866*
X06252*
Y00866*
X06252*
Y00865*
X06251*
Y00865*
X06251*
Y00864*
X0625*
Y00863*
X0625*
Y00863*
X06249*
Y00862*
X06249*
Y00862*
X06248*
Y00861*
X06248*
Y00861*
X06247*
Y0086*
X06246*
Y0086*
X06246*
Y00859*
X06245*
Y00859*
X06245*
Y00858*
X06244*
Y00857*
X06244*
Y00857*
X06243*
Y00856*
X06243*
Y00856*
X06242*
Y00855*
X06242*
Y00855*
X06241*
Y00854*
X06241*
Y00854*
X0624*
Y00853*
X06239*
Y00853*
X06239*
Y00852*
X06238*
Y00852*
X06238*
Y00851*
X06237*
Y0085*
X06237*
Y0085*
X06236*
Y00849*
X06236*
Y00849*
X06235*
Y00848*
X06235*
Y00848*
X06233*
Y00847*
X06233*
Y00847*
X06232*
Y00846*
X06232*
Y00846*
X06231*
Y00845*
X06231*
Y00845*
X0623*
Y00844*
Y00843*
Y00843*
Y00842*
Y00842*
Y00841*
Y00841*
Y0084*
Y0084*
Y00839*
Y00839*
Y00838*
Y00837*
Y00837*
Y00836*
Y00836*
Y00835*
Y00835*
Y00834*
Y00834*
Y00833*
Y00833*
Y00832*
Y00832*
Y00831*
Y0083*
Y0083*
Y00829*
Y00829*
Y00828*
Y00828*
Y00827*
Y00827*
Y00826*
Y00826*
Y00825*
Y00825*
Y00824*
Y00823*
Y00823*
Y00822*
Y00822*
Y00821*
Y00821*
Y0082*
Y0082*
Y00819*
Y00819*
Y00818*
Y00817*
Y00817*
Y00816*
Y00816*
Y00815*
Y00815*
Y00814*
Y00814*
Y00813*
Y00813*
Y00812*
Y00812*
Y00811*
Y0081*
Y0081*
Y00809*
Y00809*
Y00808*
Y00808*
Y00807*
Y00807*
Y00806*
Y00806*
Y00805*
Y00805*
Y00804*
Y00803*
Y00803*
Y00802*
Y00802*
Y00801*
X06231*
Y00801*
X06231*
Y008*
X06232*
Y008*
X06258*
Y008*
X06259*
Y00801*
X06259*
Y00801*
Y00802*
X0626*
Y00802*
Y00803*
Y00803*
Y00804*
Y00805*
Y00805*
Y00806*
Y00806*
Y00807*
Y00807*
Y00808*
Y00808*
Y00809*
Y00809*
Y0081*
Y0081*
Y00811*
Y00812*
Y00812*
Y00813*
Y00813*
Y00814*
Y00814*
Y00815*
Y00815*
Y00816*
Y00816*
Y00817*
Y00817*
Y00818*
Y00819*
Y00819*
Y0082*
Y0082*
Y00821*
Y00821*
Y00822*
Y00822*
Y00823*
Y00823*
Y00824*
Y00825*
Y00825*
Y00826*
Y00826*
Y00827*
Y00827*
Y00828*
Y00828*
Y00829*
Y00829*
Y0083*
Y0083*
Y00831*
Y00832*
Y00832*
Y00833*
Y00833*
Y00834*
Y00834*
X06261*
Y00835*
Y00835*
X06262*
Y00836*
X06298*
Y00835*
X06299*
Y00835*
Y00834*
X06299*
Y00834*
Y00833*
Y00833*
Y00832*
Y00832*
Y00831*
Y0083*
Y0083*
Y00829*
Y00829*
Y00828*
Y00828*
Y00827*
Y00827*
Y00826*
Y00826*
Y00825*
Y00825*
Y00824*
Y00823*
Y00823*
Y00822*
Y00822*
Y00821*
Y00821*
Y0082*
Y0082*
Y00819*
Y00819*
Y00818*
Y00817*
Y00817*
Y00816*
Y00816*
Y00815*
Y00815*
Y00814*
Y00814*
Y00813*
Y00813*
Y00812*
Y00812*
Y00811*
Y0081*
Y0081*
Y00809*
Y00809*
Y00808*
Y00808*
Y00807*
Y00807*
Y00806*
Y00806*
Y00805*
Y00805*
Y00804*
Y00803*
Y00803*
Y00802*
Y00802*
Y00801*
X063*
Y00801*
X06301*
Y008*
X06302*
Y008*
X06327*
Y008*
X06328*
Y00801*
X06329*
Y00801*
Y00802*
X06329*
Y00802*
Y00803*
Y00803*
Y00804*
Y00805*
Y00805*
Y00806*
Y00806*
Y00807*
Y00807*
Y00808*
Y00808*
Y00809*
Y00809*
Y0081*
Y0081*
Y00811*
Y00812*
Y00812*
Y00813*
Y00813*
Y00814*
Y00814*
Y00815*
Y00815*
Y00816*
Y00816*
Y00817*
Y00817*
Y00818*
Y00819*
Y00819*
Y0082*
Y0082*
Y00821*
Y00821*
Y00822*
Y00822*
Y00823*
Y00823*
Y00824*
Y00825*
Y00825*
Y00826*
Y00826*
Y00827*
Y00827*
Y00828*
Y00828*
Y00829*
Y00829*
Y0083*
Y0083*
Y00831*
Y00832*
Y00832*
Y00833*
Y00833*
Y00834*
Y00834*
Y00835*
Y00835*
Y00836*
Y00836*
Y00837*
Y00837*
Y00838*
Y00839*
Y00839*
Y0084*
Y0084*
Y00841*
Y00841*
Y00842*
Y00842*
Y00843*
Y00843*
Y00844*
Y00845*
Y00845*
Y00846*
Y00846*
Y00847*
Y00847*
Y00848*
Y00848*
Y00849*
Y00849*
Y0085*
Y0085*
Y00851*
Y00852*
Y00852*
Y00853*
Y00853*
Y00854*
Y00854*
Y00855*
Y00855*
Y00856*
Y00856*
Y00857*
Y00857*
Y00858*
Y00859*
Y00859*
Y0086*
Y0086*
Y00861*
Y00861*
Y00862*
Y00862*
Y00863*
Y00863*
Y00864*
Y00865*
Y00865*
Y00866*
Y00866*
Y00867*
Y00867*
Y00868*
Y00868*
Y00869*
Y00869*
Y0087*
Y0087*
Y00871*
Y00872*
Y00872*
Y00873*
Y00873*
Y00874*
Y00874*
Y00875*
Y00875*
Y00876*
Y00876*
Y00877*
Y00877*
Y00878*
Y00879*
Y00879*
Y0088*
Y0088*
Y00881*
Y00881*
Y00882*
Y00882*
Y00883*
Y00883*
Y00884*
Y00885*
Y00885*
Y00886*
Y00886*
Y00887*
Y00887*
Y00888*
Y00888*
Y00889*
Y00889*
Y0089*
Y0089*
Y00891*
Y00892*
Y00892*
Y00893*
Y00893*
Y00894*
Y00894*
Y00895*
Y00895*
Y00896*
Y00896*
Y00897*
X06329*
Y00897*
Y00898*
Y00899*
Y00899*
X06328*
Y009*
Y009*
Y00901*
X06328*
Y00901*
X06327*
Y00902*
X06326*
Y00902*
X06326*
Y00903*
X06325*
Y00903*
X06325*
Y00904*
X06324*
Y00905*
X06324*
Y00905*
X06323*
Y00906*
X06323*
Y00906*
X06322*
Y00907*
X06322*
Y00907*
X06321*
Y00908*
X06321*
Y00908*
X0632*
Y00909*
X06319*
Y00909*
X06319*
Y0091*
X06318*
Y0091*
X06318*
Y00911*
X06317*
Y00912*
X06317*
Y00912*
X06316*
Y00913*
X06316*
Y00913*
X06315*
Y00914*
X06315*
Y00914*
X06314*
Y00915*
X06314*
Y00915*
X06313*
Y00916*
X06312*
Y00916*
X06311*
Y00917*
X06309*
Y00918*
G37*
G36*
X06271Y01109D02*
X06262D01*
Y01109*
Y01108*
Y01108*
Y01107*
Y01107*
Y01106*
Y01106*
Y01105*
Y01105*
Y01104*
Y01103*
Y01103*
Y01102*
Y01102*
Y01101*
Y01101*
Y011*
Y011*
Y01099*
Y01099*
Y01098*
Y01098*
Y01097*
Y01096*
Y01096*
Y01095*
Y01095*
Y01094*
Y01094*
Y01093*
Y01093*
Y01092*
Y01092*
Y01091*
Y01091*
Y0109*
Y01089*
Y01089*
Y01088*
Y01088*
Y01087*
Y01087*
Y01086*
Y01086*
Y01085*
Y01085*
Y01084*
Y01083*
Y01083*
Y01082*
Y01082*
Y01081*
Y01081*
Y0108*
Y0108*
Y01079*
Y01079*
Y01078*
Y01078*
Y01077*
Y01076*
Y01076*
Y01075*
Y01075*
Y01074*
Y01074*
Y01073*
Y01073*
Y01072*
Y01072*
Y01071*
Y0107*
Y0107*
Y01069*
Y01069*
Y01068*
Y01068*
Y01067*
Y01067*
Y01066*
Y01066*
Y01065*
Y01065*
Y01064*
Y01063*
Y01063*
Y01062*
Y01062*
Y01061*
Y01061*
Y0106*
Y0106*
Y01059*
Y01059*
Y01058*
Y01058*
Y01057*
Y01056*
Y01056*
Y01055*
Y01055*
Y01054*
Y01054*
Y01053*
Y01053*
Y01052*
Y01052*
Y01051*
Y0105*
Y0105*
Y01049*
Y01049*
Y01048*
Y01048*
Y01047*
Y01047*
Y01046*
Y01046*
Y01045*
Y01045*
Y01044*
Y01043*
Y01043*
Y01042*
Y01042*
Y01041*
Y01041*
Y0104*
Y0104*
Y01039*
Y01039*
Y01038*
Y01038*
Y01037*
Y01036*
Y01036*
Y01035*
Y01035*
Y01034*
Y01034*
Y01033*
Y01033*
Y01032*
Y01032*
Y01031*
Y0103*
Y0103*
Y01029*
Y01029*
Y01028*
Y01028*
Y01027*
Y01027*
Y01026*
Y01026*
Y01025*
Y01025*
Y01024*
Y01023*
Y01023*
Y01022*
Y01022*
Y01021*
Y01021*
Y0102*
Y0102*
Y01019*
Y01019*
Y01018*
Y01018*
Y01017*
Y01016*
Y01016*
Y01015*
Y01015*
Y01014*
Y01014*
Y01013*
Y01013*
Y01012*
Y01012*
Y01011*
Y0101*
Y0101*
Y01009*
Y01009*
Y01008*
Y01008*
Y01007*
Y01007*
Y01006*
Y01006*
Y01005*
Y01005*
Y01004*
Y01003*
Y01003*
Y01002*
Y01002*
Y01001*
Y01001*
Y01*
Y01*
Y00999*
Y00999*
Y00998*
Y00998*
Y00997*
Y00996*
Y00996*
Y00995*
Y00995*
Y00994*
Y00994*
Y00993*
Y00993*
Y00992*
Y00992*
Y00991*
Y0099*
Y0099*
Y00989*
Y00989*
Y00988*
Y00988*
Y00987*
Y00987*
Y00986*
Y00986*
Y00985*
Y00985*
Y00984*
Y00983*
Y00983*
Y00982*
Y00982*
Y00981*
Y00981*
Y0098*
Y0098*
Y00979*
Y00979*
Y00978*
Y00978*
Y00977*
Y00976*
Y00976*
Y00975*
Y00975*
Y00974*
Y00974*
Y00973*
Y00973*
Y00972*
Y00972*
Y00971*
Y0097*
Y0097*
Y00969*
Y00969*
Y00968*
Y00968*
Y00967*
Y00967*
Y00966*
Y00966*
Y00965*
Y00965*
Y00964*
Y00963*
Y00963*
Y00962*
Y00962*
Y00961*
Y00961*
Y0096*
Y0096*
Y00959*
Y00959*
Y00958*
Y00958*
Y00957*
Y00956*
Y00956*
Y00955*
Y00955*
Y00954*
Y00954*
Y00953*
Y00953*
Y00952*
Y00952*
Y00951*
Y0095*
Y0095*
Y00949*
Y00949*
Y00948*
Y00948*
Y00947*
Y00947*
Y00946*
Y00946*
Y00945*
Y00945*
Y00944*
Y00943*
Y00943*
Y00942*
Y00942*
Y00941*
Y00941*
Y0094*
Y0094*
Y00939*
Y00939*
Y00938*
Y00938*
Y00937*
Y00936*
Y00936*
Y00935*
Y00935*
Y00934*
Y00934*
Y00933*
Y00933*
Y00932*
Y00932*
Y00931*
Y0093*
X06261*
Y0093*
X06261*
Y00929*
X0626*
Y00929*
X06259*
Y00928*
X06259*
Y00928*
X06258*
Y00927*
X06258*
Y00927*
X06257*
Y00926*
X06257*
Y00926*
X06256*
Y00925*
X06256*
Y00925*
X06255*
Y00924*
X06255*
Y00923*
X06254*
Y00923*
X06254*
Y00922*
X06253*
Y00922*
X06252*
Y00921*
X06251*
Y00921*
X06251*
Y0092*
X0625*
Y0092*
X0625*
Y00919*
X06249*
Y00919*
X06249*
Y00918*
X06248*
Y00918*
X06248*
Y00917*
X06247*
Y00916*
X06246*
Y00916*
X06246*
Y00915*
X06245*
Y00915*
X06245*
Y00914*
X06244*
Y00914*
X06244*
Y00913*
X06243*
Y00913*
X06243*
Y00912*
X06242*
Y00912*
X06242*
Y00911*
X06241*
Y0091*
X06241*
Y0091*
X0624*
Y00909*
X06239*
Y00909*
X06239*
Y00908*
X06238*
Y00908*
X06238*
Y00907*
X06237*
Y00907*
X06237*
Y00906*
X06236*
Y00906*
X06236*
Y00905*
X06235*
Y00905*
X06235*
Y00904*
X06234*
Y00903*
X06233*
Y00903*
X06233*
Y00902*
X06232*
Y00902*
X06232*
Y00901*
X06231*
Y00901*
X06231*
Y009*
X0623*
Y009*
X0623*
Y00899*
X06229*
Y00899*
X06229*
Y00898*
X06228*
Y00897*
X06228*
Y00897*
X06227*
Y00896*
X06226*
Y00896*
X06226*
Y00895*
X06225*
Y00895*
X06225*
Y00894*
X06224*
Y00894*
X06224*
Y00893*
X06223*
Y00893*
X06223*
Y00892*
X06222*
Y00892*
X06222*
Y00891*
X06221*
Y0089*
X06221*
Y0089*
X0622*
Y00889*
X06219*
Y00889*
X06219*
Y00888*
X06218*
Y00888*
X06218*
Y00887*
X06217*
Y00887*
X06217*
Y00886*
X06216*
Y00886*
X06216*
Y00885*
X06215*
Y00885*
X06214*
Y00884*
X06213*
Y00883*
X06213*
Y00883*
X06212*
Y00882*
X06212*
Y00882*
X06211*
Y00881*
X06211*
Y00881*
X0621*
Y0088*
X0621*
Y0088*
X06209*
Y00879*
X06209*
Y00879*
X06208*
Y00878*
X06208*
Y00877*
X06207*
Y00877*
X06206*
Y00876*
X06206*
Y00876*
Y00875*
X06205*
Y00875*
X06205*
Y00874*
Y00874*
X06204*
Y00873*
Y00873*
X06204*
Y00872*
Y00872*
Y00871*
Y0087*
Y0087*
Y00869*
Y00869*
Y00868*
Y00868*
Y00867*
Y00867*
Y00866*
Y00866*
Y00865*
Y00865*
Y00864*
Y00863*
Y00863*
Y00862*
Y00862*
Y00861*
Y00861*
Y0086*
Y0086*
Y00859*
Y00859*
Y00858*
Y00857*
Y00857*
Y00856*
Y00856*
Y00855*
Y00855*
Y00854*
Y00854*
Y00853*
Y00853*
Y00852*
Y00852*
Y00851*
Y0085*
Y0085*
Y00849*
Y00849*
Y00848*
X06204*
Y00848*
X06205*
Y00847*
Y00847*
X06205*
Y00846*
X06206*
Y00846*
Y00845*
X06206*
Y00845*
X06207*
Y00844*
X06208*
Y00843*
X06208*
Y00843*
X06209*
Y00842*
X06209*
Y00842*
X0621*
Y00841*
X0621*
Y00841*
X06211*
Y0084*
X06212*
Y00841*
X06212*
Y00841*
X06213*
Y00842*
X06213*
Y00842*
X06214*
Y00843*
X06215*
Y00843*
X06215*
Y00844*
X06216*
Y00845*
X06216*
Y00845*
X06217*
Y00846*
X06217*
Y00846*
X06218*
Y00847*
X06218*
Y00847*
X06219*
Y00848*
X06219*
Y00848*
X0622*
Y00849*
X06221*
Y00849*
X06221*
Y0085*
X06222*
Y0085*
X06222*
Y00851*
X06223*
Y00852*
X06223*
Y00852*
X06224*
Y00853*
X06224*
Y00853*
X06225*
Y00854*
X06226*
Y00854*
X06226*
Y00855*
X06227*
Y00855*
X06228*
Y00856*
X06228*
Y00856*
X06229*
Y00857*
X06229*
Y00857*
X0623*
Y00858*
X0623*
Y00859*
X06231*
Y00859*
X06231*
Y0086*
X06232*
Y0086*
X06232*
Y00861*
X06233*
Y00861*
X06233*
Y00862*
X06234*
Y00862*
X06235*
Y00863*
X06235*
Y00863*
X06236*
Y00864*
X06236*
Y00865*
X06237*
Y00865*
X06237*
Y00866*
X06238*
Y00866*
X06238*
Y00867*
X06239*
Y00867*
X06239*
Y00868*
X0624*
Y00868*
X06241*
Y00869*
X06241*
Y00869*
X06242*
Y0087*
X06242*
Y0087*
X06243*
Y00871*
X06243*
Y00872*
X06244*
Y00872*
X06244*
Y00873*
X06245*
Y00873*
X06245*
Y00874*
X06246*
Y00874*
X06246*
Y00875*
X06247*
Y00875*
X06248*
Y00876*
X06248*
Y00876*
X06249*
Y00877*
X06249*
Y00877*
X0625*
Y00878*
X0625*
Y00879*
X06251*
Y00879*
X06251*
Y0088*
X06252*
Y0088*
X06252*
Y00881*
X06253*
Y00881*
X06254*
Y00882*
X06254*
Y00882*
X06255*
Y00883*
X06255*
Y00883*
X06256*
Y00884*
X06256*
Y00885*
X06257*
Y00885*
X06257*
Y00886*
X06258*
Y00886*
X06258*
Y00887*
X06259*
Y00887*
X06259*
Y00888*
X0626*
Y00888*
X06261*
Y00889*
X06261*
Y00889*
X06262*
Y0089*
X06262*
Y0089*
X06263*
Y00891*
X06263*
Y00892*
X06264*
Y00892*
X06264*
Y00893*
X06265*
Y00893*
X06265*
Y00894*
X06266*
Y00894*
X06266*
Y00895*
X06267*
Y00895*
X06268*
Y00896*
X06268*
Y00896*
X06269*
Y00897*
X06269*
Y00897*
X0627*
Y00898*
X0627*
Y00899*
X06271*
Y00899*
X06272*
Y009*
X06272*
Y009*
X06273*
Y00901*
X06274*
Y00901*
X06274*
Y00902*
X06275*
Y00902*
X06275*
Y00903*
X06276*
Y00903*
X06276*
Y00904*
X06277*
Y00905*
X06277*
Y00905*
X06278*
Y00906*
X06278*
Y00906*
X06279*
Y00907*
X06279*
Y00907*
X0628*
Y00908*
X06281*
Y00908*
X06281*
Y00909*
X06282*
Y00909*
X06282*
Y0091*
X06283*
Y0091*
X06283*
Y00911*
X06284*
Y00912*
X06284*
Y00912*
X06285*
Y00913*
X06285*
Y00913*
X06286*
Y00914*
X06286*
Y00914*
X06287*
Y00915*
X06288*
Y00915*
Y00916*
X06288*
Y00916*
X06289*
Y00917*
Y00918*
X06289*
Y00918*
Y00919*
X0629*
Y00919*
Y0092*
X0629*
Y0092*
Y00921*
Y00921*
Y00922*
X06291*
Y00922*
Y00923*
Y00923*
Y00924*
Y00925*
Y00925*
Y00926*
Y00926*
Y00927*
Y00927*
Y00928*
Y00928*
Y00929*
Y00929*
Y0093*
Y0093*
Y00931*
Y00932*
Y00932*
Y00933*
Y00933*
Y00934*
Y00934*
Y00935*
Y00935*
Y00936*
Y00936*
Y00937*
Y00938*
Y00938*
Y00939*
Y00939*
Y0094*
Y0094*
Y00941*
Y00941*
Y00942*
Y00942*
Y00943*
Y00943*
Y00944*
Y00945*
Y00945*
Y00946*
Y00946*
Y00947*
Y00947*
Y00948*
Y00948*
Y00949*
Y00949*
Y0095*
Y0095*
Y00951*
Y00952*
Y00952*
Y00953*
Y00953*
Y00954*
Y00954*
Y00955*
Y00955*
Y00956*
Y00956*
Y00957*
Y00958*
Y00958*
Y00959*
Y00959*
Y0096*
Y0096*
Y00961*
Y00961*
Y00962*
Y00962*
Y00963*
Y00963*
Y00964*
Y00965*
Y00965*
Y00966*
Y00966*
Y00967*
Y00967*
Y00968*
Y00968*
Y00969*
Y00969*
Y0097*
Y0097*
Y00971*
Y00972*
Y00972*
Y00973*
Y00973*
Y00974*
Y00974*
Y00975*
Y00975*
Y00976*
Y00976*
Y00977*
Y00978*
Y00978*
Y00979*
Y00979*
Y0098*
Y0098*
Y00981*
Y00981*
Y00982*
Y00982*
Y00983*
Y00983*
Y00984*
Y00985*
Y00985*
Y00986*
Y00986*
Y00987*
Y00987*
Y00988*
Y00988*
Y00989*
Y00989*
Y0099*
Y0099*
Y00991*
Y00992*
Y00992*
Y00993*
Y00993*
Y00994*
Y00994*
Y00995*
Y00995*
Y00996*
Y00996*
Y00997*
Y00998*
Y00998*
Y00999*
Y00999*
Y01*
Y01*
Y01001*
Y01001*
Y01002*
Y01002*
Y01003*
Y01003*
Y01004*
Y01005*
Y01005*
Y01006*
Y01006*
Y01007*
Y01007*
Y01008*
Y01008*
Y01009*
Y01009*
Y0101*
Y0101*
Y01011*
Y01012*
Y01012*
Y01013*
Y01013*
Y01014*
Y01014*
Y01015*
Y01015*
Y01016*
Y01016*
Y01017*
Y01018*
Y01018*
Y01019*
Y01019*
Y0102*
Y0102*
Y01021*
Y01021*
Y01022*
Y01022*
Y01023*
Y01023*
Y01024*
Y01025*
Y01025*
Y01026*
Y01026*
Y01027*
Y01027*
Y01028*
Y01028*
Y01029*
Y01029*
Y0103*
Y0103*
Y01031*
Y01032*
Y01032*
Y01033*
Y01033*
Y01034*
Y01034*
Y01035*
Y01035*
Y01036*
Y01036*
Y01037*
Y01038*
Y01038*
Y01039*
Y01039*
Y0104*
Y0104*
Y01041*
Y01041*
Y01042*
Y01042*
Y01043*
Y01043*
Y01044*
Y01045*
Y01045*
Y01046*
Y01046*
Y01047*
Y01047*
Y01048*
Y01048*
Y01049*
Y01049*
Y0105*
Y0105*
Y01051*
Y01052*
Y01052*
Y01053*
Y01053*
Y01054*
Y01054*
Y01055*
Y01055*
Y01056*
Y01056*
Y01057*
Y01058*
Y01058*
Y01059*
Y01059*
Y0106*
Y0106*
Y01061*
Y01061*
Y01062*
Y01062*
Y01063*
Y01063*
Y01064*
Y01065*
Y01065*
Y01066*
Y01066*
Y01067*
Y01067*
Y01068*
Y01068*
Y01069*
Y01069*
Y0107*
Y0107*
Y01071*
Y01072*
Y01072*
Y01073*
Y01073*
Y01074*
Y01074*
Y01075*
Y01075*
Y01076*
Y01076*
Y01077*
Y01078*
Y01078*
Y01079*
Y01079*
Y0108*
Y0108*
Y01081*
Y01081*
Y01082*
Y01082*
Y01083*
Y01083*
Y01084*
Y01085*
Y01085*
Y01086*
Y01086*
Y01087*
Y01087*
Y01088*
Y01088*
Y01089*
Y01089*
Y0109*
X0629*
Y01091*
Y01091*
Y01092*
Y01092*
X0629*
Y01093*
Y01093*
X06289*
Y01094*
X06289*
Y01094*
X06288*
Y01095*
X06288*
Y01095*
X06287*
Y01096*
X06286*
Y01096*
X06286*
Y01097*
X06285*
Y01098*
X06285*
Y01098*
X06284*
Y01099*
X06284*
Y01099*
X06283*
Y011*
X06283*
Y011*
X06282*
Y01101*
X06282*
Y01101*
X06281*
Y01102*
X06281*
Y01102*
X0628*
Y01103*
X06279*
Y01103*
X06279*
Y01104*
X06278*
Y01105*
X06278*
Y01105*
X06277*
Y01106*
X06277*
Y01106*
X06276*
Y01107*
X06276*
Y01107*
X06275*
Y01108*
X06275*
Y01108*
X06274*
Y01109*
X06271*
Y01109*
G37*
G36*
X06533Y00918D02*
X06458D01*
Y00917*
X06457*
Y00916*
X06457*
Y00916*
X06456*
Y00915*
X06456*
Y00915*
Y00914*
Y00914*
Y00913*
Y00913*
Y00912*
Y00912*
Y00911*
Y0091*
Y0091*
Y00909*
Y00909*
Y00908*
Y00908*
Y00907*
Y00907*
Y00906*
Y00906*
Y00905*
Y00905*
Y00904*
Y00903*
Y00903*
Y00902*
Y00902*
Y00901*
Y00901*
Y009*
Y009*
Y00899*
Y00899*
Y00898*
Y00897*
Y00897*
Y00896*
Y00896*
Y00895*
Y00895*
Y00894*
Y00894*
Y00893*
Y00893*
Y00892*
Y00892*
Y00891*
Y0089*
Y0089*
Y00889*
Y00889*
Y00888*
Y00888*
Y00887*
Y00887*
Y00886*
Y00886*
Y00885*
Y00885*
Y00884*
Y00883*
Y00883*
Y00882*
Y00882*
Y00881*
Y00881*
Y0088*
Y0088*
Y00879*
Y00879*
Y00878*
Y00877*
Y00877*
Y00876*
Y00876*
Y00875*
Y00875*
Y00874*
Y00874*
Y00873*
Y00873*
Y00872*
Y00872*
Y00871*
Y0087*
Y0087*
Y00869*
Y00869*
Y00868*
Y00868*
Y00867*
Y00867*
Y00866*
Y00866*
Y00865*
Y00865*
Y00864*
Y00863*
Y00863*
Y00862*
Y00862*
Y00861*
Y00861*
Y0086*
Y0086*
Y00859*
Y00859*
Y00858*
Y00857*
Y00857*
Y00856*
Y00856*
Y00855*
Y00855*
Y00854*
Y00854*
Y00853*
Y00853*
Y00852*
Y00852*
Y00851*
Y0085*
Y0085*
Y00849*
Y00849*
Y00848*
Y00848*
Y00847*
Y00847*
Y00846*
Y00846*
Y00845*
Y00845*
Y00844*
Y00843*
Y00843*
Y00842*
Y00842*
Y00841*
Y00841*
Y0084*
Y0084*
Y00839*
Y00839*
Y00838*
Y00837*
Y00837*
Y00836*
Y00836*
Y00835*
Y00835*
Y00834*
Y00834*
Y00833*
Y00833*
Y00832*
Y00832*
Y00831*
Y0083*
Y0083*
Y00829*
Y00829*
Y00828*
Y00828*
Y00827*
Y00827*
Y00826*
Y00826*
Y00825*
Y00825*
Y00824*
Y00823*
Y00823*
Y00822*
Y00822*
Y00821*
Y00821*
Y0082*
Y0082*
Y00819*
Y00819*
Y00818*
Y00817*
Y00817*
Y00816*
Y00816*
Y00815*
Y00815*
Y00814*
Y00814*
Y00813*
Y00813*
Y00812*
Y00812*
Y00811*
Y0081*
Y0081*
Y00809*
Y00809*
Y00808*
Y00808*
Y00807*
Y00807*
Y00806*
Y00806*
Y00805*
Y00805*
Y00804*
Y00803*
Y00803*
Y00802*
Y00802*
Y00801*
X06456*
Y00801*
X06457*
Y008*
X06457*
Y008*
X06535*
Y008*
X06537*
Y00801*
X06538*
Y00801*
X06538*
Y00802*
X06539*
Y00802*
X06539*
Y00803*
X0654*
Y00803*
X06541*
Y00804*
X06541*
Y00805*
X06542*
Y00805*
X06542*
Y00806*
X06543*
Y00806*
X06543*
Y00807*
X06544*
Y00807*
X06544*
Y00808*
X06545*
Y00808*
X06545*
Y00809*
X06546*
Y00809*
X06547*
Y0081*
X06547*
Y0081*
X06548*
Y00811*
X06548*
Y00812*
X06549*
Y00812*
X06549*
Y00813*
X0655*
Y00813*
X0655*
Y00814*
X06551*
Y00814*
X06551*
Y00815*
X06552*
Y00815*
X06552*
Y00816*
X06553*
Y00816*
X06554*
Y00817*
Y00817*
Y00818*
X06554*
Y00819*
Y00819*
Y0082*
Y0082*
X06555*
Y00821*
Y00821*
Y00822*
Y00822*
Y00823*
Y00823*
Y00824*
Y00825*
Y00825*
Y00826*
Y00826*
Y00827*
Y00827*
Y00828*
Y00828*
Y00829*
Y00829*
Y0083*
Y0083*
Y00831*
Y00832*
Y00832*
Y00833*
Y00833*
Y00834*
Y00834*
Y00835*
Y00835*
Y00836*
Y00836*
Y00837*
Y00837*
Y00838*
Y00839*
Y00839*
Y0084*
Y0084*
Y00841*
Y00841*
Y00842*
Y00842*
Y00843*
Y00843*
Y00844*
Y00845*
Y00845*
Y00846*
Y00846*
Y00847*
Y00847*
Y00848*
Y00848*
Y00849*
Y00849*
Y0085*
Y0085*
Y00851*
Y00852*
Y00852*
Y00853*
Y00853*
Y00854*
Y00854*
Y00855*
Y00855*
Y00856*
Y00856*
Y00857*
Y00857*
Y00858*
Y00859*
Y00859*
Y0086*
Y0086*
Y00861*
Y00861*
Y00862*
Y00862*
Y00863*
Y00863*
Y00864*
Y00865*
Y00865*
Y00866*
Y00866*
Y00867*
Y00867*
Y00868*
Y00868*
Y00869*
Y00869*
Y0087*
Y0087*
Y00871*
Y00872*
Y00872*
Y00873*
Y00873*
Y00874*
Y00874*
Y00875*
Y00875*
Y00876*
Y00876*
Y00877*
Y00877*
Y00878*
Y00879*
Y00879*
Y0088*
Y0088*
Y00881*
Y00881*
Y00882*
Y00882*
Y00883*
Y00883*
Y00884*
Y00885*
Y00885*
Y00886*
Y00886*
Y00887*
Y00887*
Y00888*
Y00888*
Y00889*
Y00889*
Y0089*
Y0089*
Y00891*
Y00892*
Y00892*
Y00893*
Y00893*
Y00894*
Y00894*
Y00895*
Y00895*
Y00896*
Y00896*
Y00897*
X06554*
Y00897*
Y00898*
Y00899*
Y00899*
X06554*
Y009*
Y009*
X06553*
Y00901*
X06552*
Y00901*
X06552*
Y00902*
X06551*
Y00902*
X06551*
Y00903*
X0655*
Y00903*
X0655*
Y00904*
X06549*
Y00905*
X06549*
Y00905*
X06548*
Y00906*
X06548*
Y00906*
X06547*
Y00907*
X06547*
Y00907*
X06546*
Y00908*
X06545*
Y00908*
X06545*
Y00909*
X06544*
Y00909*
X06544*
Y0091*
X06543*
Y0091*
X06543*
Y00911*
X06542*
Y00912*
X06542*
Y00912*
X06541*
Y00913*
X06541*
Y00913*
X0654*
Y00914*
X06539*
Y00914*
X06539*
Y00915*
X06538*
Y00915*
X06538*
Y00916*
X06537*
Y00916*
X06536*
Y00917*
X06533*
Y00918*
G37*
G36*
X06418D02*
X06343D01*
Y00917*
X06342*
Y00916*
X06342*
Y00916*
X06341*
Y00915*
Y00915*
Y00914*
X06341*
Y00914*
Y00913*
Y00913*
Y00912*
Y00912*
Y00911*
Y0091*
Y0091*
Y00909*
Y00909*
Y00908*
Y00908*
Y00907*
Y00907*
Y00906*
Y00906*
Y00905*
Y00905*
Y00904*
Y00903*
Y00903*
Y00902*
Y00902*
Y00901*
Y00901*
Y009*
Y009*
Y00899*
Y00899*
Y00898*
Y00897*
Y00897*
Y00896*
Y00896*
Y00895*
Y00895*
Y00894*
Y00894*
Y00893*
Y00893*
Y00892*
Y00892*
Y00891*
Y0089*
Y0089*
Y00889*
Y00889*
Y00888*
Y00888*
Y00887*
Y00887*
Y00886*
Y00886*
Y00885*
Y00885*
Y00884*
Y00883*
Y00883*
Y00882*
Y00882*
Y00881*
Y00881*
Y0088*
Y0088*
Y00879*
Y00879*
Y00878*
Y00877*
Y00877*
Y00876*
Y00876*
Y00875*
Y00875*
Y00874*
Y00874*
Y00873*
Y00873*
Y00872*
Y00872*
Y00871*
Y0087*
Y0087*
Y00869*
Y00869*
Y00868*
Y00868*
Y00867*
Y00867*
Y00866*
Y00866*
Y00865*
Y00865*
Y00864*
Y00863*
Y00863*
Y00862*
Y00862*
Y00861*
Y00861*
Y0086*
Y0086*
Y00859*
Y00859*
Y00858*
Y00857*
Y00857*
Y00856*
Y00856*
Y00855*
Y00855*
Y00854*
Y00854*
Y00853*
Y00853*
Y00852*
Y00852*
Y00851*
Y0085*
Y0085*
Y00849*
Y00849*
Y00848*
Y00848*
Y00847*
Y00847*
Y00846*
Y00846*
Y00845*
Y00845*
Y00844*
Y00843*
Y00843*
Y00842*
Y00842*
Y00841*
Y00841*
Y0084*
Y0084*
Y00839*
Y00839*
Y00838*
Y00837*
Y00837*
Y00836*
Y00836*
Y00835*
Y00835*
Y00834*
Y00834*
Y00833*
Y00833*
Y00832*
Y00832*
Y00831*
Y0083*
Y0083*
Y00829*
Y00829*
Y00828*
Y00828*
Y00827*
Y00827*
Y00826*
Y00826*
Y00825*
Y00825*
Y00824*
Y00823*
Y00823*
Y00822*
Y00822*
Y00821*
Y00821*
Y0082*
Y0082*
Y00819*
Y00819*
Y00818*
Y00817*
Y00817*
Y00816*
Y00816*
Y00815*
Y00815*
Y00814*
Y00814*
Y00813*
Y00813*
Y00812*
Y00812*
Y00811*
Y0081*
Y0081*
Y00809*
Y00809*
Y00808*
Y00808*
Y00807*
Y00807*
Y00806*
Y00806*
Y00805*
Y00805*
Y00804*
Y00803*
X06341*
Y00803*
X06341*
Y00802*
X06341*
Y00802*
Y00801*
Y00801*
X06342*
Y008*
X06343*
Y008*
X06369*
Y008*
X0637*
Y00801*
X0637*
Y00801*
Y00802*
Y00802*
X06371*
Y00803*
Y00803*
Y00804*
Y00805*
Y00805*
Y00806*
Y00806*
Y00807*
Y00807*
Y00808*
Y00808*
Y00809*
Y00809*
Y0081*
Y0081*
Y00811*
Y00812*
Y00812*
Y00813*
Y00813*
Y00814*
Y00814*
Y00815*
Y00815*
Y00816*
Y00816*
Y00817*
Y00817*
Y00818*
Y00819*
Y00819*
Y0082*
Y0082*
Y00821*
Y00821*
Y00822*
Y00822*
Y00823*
Y00823*
Y00824*
Y00825*
Y00825*
Y00826*
Y00826*
Y00827*
Y00827*
Y00828*
Y00828*
Y00829*
Y00829*
Y0083*
Y0083*
Y00831*
Y00832*
X0637*
Y00832*
X06371*
Y00833*
Y00833*
Y00834*
Y00834*
Y00835*
X06391*
Y00834*
Y00834*
X06392*
Y00833*
Y00833*
X06392*
Y00832*
X06393*
Y00832*
Y00831*
X06394*
Y0083*
Y0083*
X06394*
Y00829*
X06395*
Y00829*
Y00828*
X06395*
Y00828*
Y00827*
X06396*
Y00827*
Y00826*
X06396*
Y00826*
X06397*
Y00825*
Y00825*
X06397*
Y00824*
Y00823*
X06398*
Y00823*
X06398*
Y00822*
Y00822*
X06399*
Y00821*
Y00821*
X06399*
Y0082*
X064*
Y0082*
Y00819*
X06401*
Y00819*
Y00818*
X06401*
Y00817*
Y00817*
X06402*
Y00816*
X06402*
Y00816*
Y00815*
X06403*
Y00815*
Y00814*
X06403*
Y00814*
X06404*
Y00813*
Y00813*
X06404*
Y00812*
Y00812*
X06405*
Y00811*
X06405*
Y0081*
Y0081*
X06406*
Y00809*
Y00809*
X06406*
Y00808*
X06407*
Y00808*
Y00807*
X06408*
Y00807*
Y00806*
X06408*
Y00806*
Y00805*
X06409*
Y00805*
X06409*
Y00804*
Y00803*
X0641*
Y00803*
Y00802*
X0641*
Y00802*
X06411*
Y00801*
X06411*
Y00801*
X06412*
Y008*
X06413*
Y008*
X06443*
Y008*
X06444*
Y00801*
Y00801*
Y00802*
Y00802*
X06443*
Y00803*
X06443*
Y00803*
Y00804*
X06442*
Y00805*
Y00805*
X06442*
Y00806*
X06441*
Y00806*
Y00807*
X06441*
Y00807*
Y00808*
X0644*
Y00808*
X06439*
Y00809*
Y00809*
X06439*
Y0081*
Y0081*
X06438*
Y00811*
X06438*
Y00812*
Y00812*
X06437*
Y00813*
Y00813*
X06437*
Y00814*
X06436*
Y00814*
Y00815*
X06436*
Y00815*
Y00816*
X06435*
Y00816*
X06435*
Y00817*
Y00817*
X06434*
Y00818*
Y00819*
X06434*
Y00819*
X06433*
Y0082*
Y0082*
X06432*
Y00821*
Y00821*
X06432*
Y00822*
X06431*
Y00822*
Y00823*
X06431*
Y00823*
Y00824*
X0643*
Y00825*
X0643*
Y00825*
Y00826*
X06429*
Y00826*
Y00827*
X06429*
Y00827*
X06428*
Y00828*
Y00828*
X06428*
Y00829*
Y00829*
X06427*
Y0083*
X06427*
Y0083*
Y00831*
X06426*
Y00832*
Y00832*
X06425*
Y00833*
Y00833*
X06425*
Y00834*
X06424*
Y00834*
Y00835*
X06424*
Y00835*
Y00836*
X06423*
Y00836*
X06423*
Y00837*
Y00837*
X06423*
Y00838*
X06424*
Y00839*
X06424*
Y00839*
X06425*
Y0084*
X06425*
Y0084*
X06426*
Y00841*
X06427*
Y00841*
X06427*
Y00842*
X06428*
Y00842*
X06428*
Y00843*
X06429*
Y00843*
X06429*
Y00844*
X0643*
Y00845*
X0643*
Y00845*
X06431*
Y00846*
X06431*
Y00846*
X06432*
Y00847*
X06432*
Y00847*
X06433*
Y00848*
X06434*
Y00848*
X06434*
Y00849*
X06435*
Y00849*
X06435*
Y0085*
Y0085*
X06436*
Y00851*
X06436*
Y00852*
X06437*
Y00852*
X06437*
Y00853*
X06438*
Y00853*
X06438*
Y00854*
Y00854*
X06439*
Y00855*
Y00855*
X06439*
Y00856*
Y00856*
Y00857*
Y00857*
Y00858*
Y00859*
Y00859*
Y0086*
Y0086*
Y00861*
Y00861*
Y00862*
Y00862*
Y00863*
Y00863*
Y00864*
Y00865*
Y00865*
Y00866*
Y00866*
Y00867*
Y00867*
Y00868*
Y00868*
Y00869*
Y00869*
Y0087*
Y0087*
Y00871*
Y00872*
Y00872*
Y00873*
Y00873*
Y00874*
Y00874*
Y00875*
Y00875*
Y00876*
Y00876*
Y00877*
Y00877*
Y00878*
Y00879*
Y00879*
Y0088*
Y0088*
Y00881*
Y00881*
Y00882*
Y00882*
Y00883*
Y00883*
Y00884*
Y00885*
Y00885*
Y00886*
Y00886*
Y00887*
Y00887*
Y00888*
Y00888*
Y00889*
Y00889*
Y0089*
Y0089*
Y00891*
Y00892*
Y00892*
Y00893*
Y00893*
Y00894*
Y00894*
Y00895*
Y00895*
Y00896*
Y00896*
Y00897*
Y00897*
Y00898*
X06439*
Y00899*
Y00899*
Y009*
X06438*
Y009*
Y00901*
X06438*
Y00901*
X06437*
Y00902*
X06437*
Y00902*
X06436*
Y00903*
X06436*
Y00903*
X06435*
Y00904*
X06435*
Y00905*
X06434*
Y00905*
X06434*
Y00906*
X06433*
Y00906*
X06432*
Y00907*
X06432*
Y00907*
X06431*
Y00908*
X06431*
Y00908*
X0643*
Y00909*
X0643*
Y00909*
X06429*
Y0091*
X06429*
Y0091*
X06428*
Y00911*
X06428*
Y00912*
X06427*
Y00912*
X06427*
Y00913*
X06426*
Y00913*
X06425*
Y00914*
X06425*
Y00914*
X06424*
Y00915*
X06424*
Y00915*
X06423*
Y00916*
X06422*
Y00916*
X06421*
Y00917*
X06418*
Y00918*
G37*
G36*
X06077Y00917D02*
X06071D01*
Y00916*
Y00916*
Y00915*
Y00915*
Y00914*
Y00914*
Y00913*
Y00913*
Y00912*
Y00912*
Y00911*
X06071*
Y0091*
Y0091*
Y00909*
Y00909*
Y00908*
Y00908*
Y00907*
Y00907*
Y00906*
Y00906*
Y00905*
X06072*
Y00905*
X06071*
Y00904*
X06072*
Y00903*
Y00903*
Y00902*
Y00902*
Y00901*
Y00901*
Y009*
Y009*
Y00899*
Y00899*
X06072*
Y00898*
Y00897*
Y00897*
Y00896*
Y00896*
Y00895*
Y00895*
Y00894*
X06073*
Y00894*
Y00893*
Y00893*
Y00892*
Y00892*
Y00891*
Y0089*
X06073*
Y0089*
Y00889*
Y00889*
Y00888*
Y00888*
Y00887*
X06074*
Y00887*
Y00886*
Y00886*
Y00885*
Y00885*
X06075*
Y00884*
Y00883*
Y00883*
Y00882*
Y00882*
X06075*
Y00881*
Y00881*
Y0088*
Y0088*
Y00879*
X06076*
Y00879*
Y00878*
Y00877*
Y00877*
Y00876*
X06076*
Y00876*
Y00875*
Y00875*
Y00874*
X06077*
Y00874*
Y00873*
Y00873*
Y00872*
X06077*
Y00872*
Y00871*
Y0087*
Y0087*
X06078*
Y00869*
Y00869*
Y00868*
Y00868*
X06078*
Y00867*
Y00867*
Y00866*
X06079*
Y00866*
Y00865*
Y00865*
Y00864*
X06079*
Y00863*
Y00863*
Y00862*
X0608*
Y00862*
Y00861*
Y00861*
X06081*
Y0086*
Y0086*
Y00859*
X06081*
Y00859*
Y00858*
Y00857*
X06082*
Y00857*
Y00856*
Y00856*
X06082*
Y00855*
Y00855*
Y00854*
X06083*
Y00854*
Y00853*
Y00853*
X06083*
Y00852*
Y00852*
Y00851*
X06084*
Y0085*
Y0085*
Y00849*
X06084*
Y00849*
Y00848*
X06085*
Y00848*
Y00847*
Y00847*
X06085*
Y00846*
Y00846*
X06086*
Y00845*
Y00845*
Y00844*
X06086*
Y00843*
Y00843*
X06087*
Y00842*
Y00842*
Y00841*
X06088*
Y00841*
Y0084*
X06088*
Y0084*
Y00839*
X06089*
Y00839*
Y00838*
Y00837*
X06089*
Y00837*
Y00836*
X0609*
Y00836*
Y00835*
X0609*
Y00835*
Y00834*
X06091*
Y00834*
Y00833*
X06091*
Y00833*
Y00832*
X06092*
Y00832*
Y00831*
X06092*
Y0083*
Y0083*
X06093*
Y00829*
Y00829*
X06093*
Y00828*
Y00828*
X06094*
Y00827*
Y00827*
X06095*
Y00826*
Y00826*
X06095*
Y00825*
Y00825*
X06096*
Y00824*
Y00823*
X06096*
Y00823*
X06097*
Y00822*
Y00822*
X06097*
Y00821*
Y00821*
X06098*
Y0082*
Y0082*
X06098*
Y00819*
Y00819*
X06099*
Y00818*
X06099*
Y00817*
Y00817*
X061*
Y00816*
Y00816*
X06101*
Y00815*
Y00815*
X06101*
Y00814*
X06102*
Y00814*
Y00813*
X06102*
Y00813*
X06103*
Y00812*
Y00812*
X06103*
Y00811*
Y0081*
X06104*
Y0081*
X06104*
Y00809*
Y00809*
X06105*
Y00808*
X06105*
Y00808*
Y00807*
X06106*
Y00807*
X06106*
Y00806*
Y00806*
X06107*
Y00805*
X06108*
Y00805*
Y00804*
X06108*
Y00803*
X06109*
Y00803*
X06109*
Y00802*
Y00802*
X0611*
Y00801*
X0611*
Y00801*
Y008*
X06111*
Y008*
X06111*
Y00799*
X06112*
Y00799*
Y00798*
X06112*
Y00797*
X06113*
Y00797*
X06113*
Y00796*
Y00796*
X06114*
Y00795*
X06115*
Y00795*
X06115*
Y00794*
X06116*
Y00794*
Y00793*
X06116*
Y00793*
X06117*
Y00792*
X06117*
Y00792*
X06118*
Y00791*
Y0079*
X06118*
Y0079*
X06119*
Y00789*
X06119*
Y00789*
X0612*
Y00788*
Y00788*
X06121*
Y00787*
X06121*
Y00787*
X06122*
Y00786*
X06122*
Y00786*
X06123*
Y00785*
X06123*
Y00785*
X06124*
Y00784*
Y00783*
X06124*
Y00783*
X06125*
Y00782*
X06125*
Y00782*
X06126*
Y00781*
X06126*
Y00781*
X06127*
Y0078*
X06128*
Y0078*
X06128*
Y00779*
X06129*
Y00779*
X06129*
Y00778*
X0613*
Y00777*
X0613*
Y00777*
X06131*
Y00776*
X06131*
Y00776*
X06132*
Y00775*
X06132*
Y00775*
X06133*
Y00774*
X06133*
Y00774*
X06134*
Y00773*
X06135*
Y00773*
X06135*
Y00772*
X06136*
Y00772*
X06136*
Y00771*
X06137*
Y0077*
X06137*
Y0077*
X06138*
Y00769*
X06138*
Y00769*
X06139*
Y00768*
X06139*
Y00768*
X0614*
Y00767*
X06141*
Y00767*
X06142*
Y00766*
X06142*
Y00766*
X06143*
Y00765*
X06143*
Y00765*
X06144*
Y00764*
X06144*
Y00763*
X06145*
Y00763*
X06146*
Y00762*
X06146*
Y00762*
X06147*
Y00761*
X06148*
Y00761*
X06149*
Y0076*
X06149*
Y0076*
X0615*
Y00759*
X0615*
Y00759*
X06151*
Y00758*
X06152*
Y00757*
X06152*
Y00757*
X06153*
Y00756*
X06154*
Y00756*
X06155*
Y00755*
X06156*
Y00755*
X06156*
Y00754*
X06157*
Y00754*
X06158*
Y00753*
X06158*
Y00753*
X06159*
Y00752*
X0616*
Y00752*
X06161*
Y00751*
X06162*
Y0075*
X06162*
Y0075*
X06163*
Y00749*
X06164*
Y00749*
X06165*
Y00748*
X06165*
Y00748*
X06166*
Y00747*
X06167*
Y00747*
X06168*
Y00746*
X06169*
Y00746*
X0617*
Y00745*
X06171*
Y00745*
X06171*
Y00744*
X06172*
Y00743*
X06173*
Y00743*
X06174*
Y00742*
X06175*
Y00742*
X06176*
Y00741*
X06177*
Y00741*
X06178*
Y0074*
X06179*
Y0074*
X0618*
Y00739*
X06181*
Y00739*
X06182*
Y00738*
X06183*
Y00737*
X06184*
Y00737*
X06185*
Y00736*
X06186*
Y00736*
X06188*
Y00735*
X06189*
Y00735*
X0619*
Y00734*
X06191*
Y00734*
X06192*
Y00733*
X06193*
Y00733*
X06194*
Y00732*
X06196*
Y00732*
X06197*
Y00731*
X06198*
Y0073*
X06199*
Y0073*
X06201*
Y00729*
X06202*
Y00729*
X06203*
Y00728*
X06205*
Y00728*
X06206*
Y00727*
X06208*
Y00727*
X06209*
Y00726*
X06211*
Y00726*
X06212*
Y00725*
X06213*
Y00725*
X06215*
Y00724*
X06217*
Y00723*
X06219*
Y00723*
X06221*
Y00722*
X06223*
Y00722*
X06224*
Y00721*
X06226*
Y00721*
X06229*
Y0072*
X06231*
Y0072*
X06233*
Y00719*
X06236*
Y00719*
X06238*
Y00718*
X06241*
Y00717*
X06244*
Y00717*
X06247*
Y00716*
X06251*
Y00716*
X06255*
Y00715*
X0626*
Y00715*
X06266*
Y00714*
X06292*
Y00715*
X06299*
Y00715*
X06304*
Y00716*
X06309*
Y00716*
X06312*
Y00717*
X06316*
Y00717*
X06318*
Y00718*
X06322*
Y00719*
X06324*
Y00719*
X06326*
Y0072*
X06329*
Y0072*
X06331*
Y00721*
X06333*
Y00721*
X06335*
Y00722*
X06337*
Y00722*
X06339*
Y00723*
X06341*
Y00723*
X06342*
Y00724*
X06344*
Y00725*
X06345*
Y00725*
X06347*
Y00726*
X06349*
Y00726*
X0635*
Y00727*
X06352*
Y00727*
X06354*
Y00728*
X06355*
Y00728*
X06356*
Y00729*
X06357*
Y00729*
X06359*
Y0073*
X0636*
Y0073*
X06362*
Y00731*
X06363*
Y00732*
X06364*
Y00732*
X06365*
Y00733*
X06366*
Y00733*
X06368*
Y00734*
X06369*
Y00734*
X0637*
Y00735*
X06371*
Y00735*
X06372*
Y00736*
X06373*
Y00736*
X06374*
Y00737*
X06375*
Y00737*
X06376*
Y00738*
X06377*
Y00739*
X06378*
Y00739*
X06379*
Y0074*
X06381*
Y0074*
X06381*
Y00741*
X06382*
Y00741*
X06383*
Y00742*
X06384*
Y00742*
X06385*
Y00743*
X06386*
Y00743*
X06387*
Y00744*
X06388*
Y00745*
X06389*
Y00745*
X0639*
Y00746*
X0639*
Y00746*
X06391*
Y00747*
X06392*
Y00747*
X06393*
Y00748*
X06394*
Y00748*
X06395*
Y00749*
X06396*
Y00749*
X06396*
Y0075*
X06397*
Y0075*
X06398*
Y00751*
X06398*
Y00752*
X06399*
Y00752*
X064*
Y00753*
X06401*
Y00753*
X06402*
Y00754*
X06403*
Y00754*
X06403*
Y00755*
X06404*
Y00755*
X06405*
Y00756*
X06405*
Y00756*
X06406*
Y00757*
X06407*
Y00757*
X06408*
Y00758*
X06408*
Y00759*
X06409*
Y00759*
X0641*
Y0076*
X0641*
Y0076*
X06411*
Y00761*
X06411*
Y00761*
X06412*
Y00762*
X06413*
Y00762*
X06414*
Y00763*
X06414*
Y00763*
X06415*
Y00764*
X06416*
Y00765*
X06416*
Y00765*
X06417*
Y00766*
X06417*
Y00766*
X06418*
Y00767*
X06418*
Y00767*
X06419*
Y00768*
X0642*
Y00768*
X06421*
Y00769*
X06421*
Y00769*
X06422*
Y0077*
X06422*
Y0077*
X06423*
Y00771*
X06423*
Y00772*
X06424*
Y00772*
X06424*
Y00773*
X06425*
Y00773*
X06425*
Y00774*
X06426*
Y00774*
X06427*
Y00775*
X06427*
Y00775*
X06428*
Y00776*
X06428*
Y00776*
X06429*
Y00777*
X06429*
Y00777*
X0643*
Y00778*
X0643*
Y00779*
X06431*
Y00779*
X06431*
Y0078*
X06432*
Y0078*
X06432*
Y00781*
X06433*
Y00781*
X06434*
Y00782*
X06434*
Y00782*
X06435*
Y00783*
X06435*
Y00783*
Y00784*
X06436*
Y00785*
X06436*
Y00785*
X06437*
Y00786*
X06437*
Y00786*
X06438*
Y00787*
X06438*
Y00787*
X06439*
Y00788*
Y00788*
X06439*
Y00789*
X06431*
Y00788*
X0643*
Y00788*
X0643*
Y00787*
Y00787*
X06429*
Y00786*
X06429*
Y00786*
X06428*
Y00785*
X06428*
Y00785*
X06427*
Y00784*
X06427*
Y00783*
X06426*
Y00783*
X06425*
Y00782*
X06425*
Y00782*
X06424*
Y00781*
X06424*
Y00781*
X06423*
Y0078*
X06423*
Y0078*
X06422*
Y00779*
X06422*
Y00779*
X06421*
Y00778*
X06421*
Y00777*
X0642*
Y00777*
X06419*
Y00776*
X06419*
Y00776*
X06418*
Y00775*
X06418*
Y00775*
X06417*
Y00774*
X06417*
Y00774*
X06416*
Y00773*
X06415*
Y00773*
X06415*
Y00772*
X06414*
Y00772*
X06414*
Y00771*
X06413*
Y0077*
X06412*
Y0077*
X06412*
Y00769*
X06411*
Y00769*
X0641*
Y00768*
X0641*
Y00768*
X06409*
Y00767*
X06409*
Y00767*
X06408*
Y00766*
X06407*
Y00766*
X06406*
Y00765*
X06406*
Y00765*
X06405*
Y00764*
X06404*
Y00763*
X06404*
Y00763*
X06403*
Y00762*
X06402*
Y00762*
X06402*
Y00761*
X06401*
Y00761*
X064*
Y0076*
X06399*
Y0076*
X06399*
Y00759*
X06398*
Y00759*
X06397*
Y00758*
X06396*
Y00757*
X06396*
Y00757*
X06395*
Y00756*
X06394*
Y00756*
X06394*
Y00755*
X06392*
Y00755*
X06392*
Y00754*
X06391*
Y00754*
X0639*
Y00753*
X06389*
Y00753*
X06389*
Y00752*
X06388*
Y00752*
X06386*
Y00751*
X06386*
Y0075*
X06385*
Y0075*
X06384*
Y00749*
X06383*
Y00749*
X06382*
Y00748*
X06381*
Y00748*
X06381*
Y00747*
X06379*
Y00747*
X06378*
Y00746*
X06377*
Y00746*
X06377*
Y00745*
X06376*
Y00745*
X06375*
Y00744*
X06374*
Y00743*
X06372*
Y00743*
X06371*
Y00742*
X0637*
Y00742*
X06369*
Y00741*
X06368*
Y00741*
X06367*
Y0074*
X06366*
Y0074*
X06365*
Y00739*
X06364*
Y00739*
X06363*
Y00738*
X06361*
Y00737*
X0636*
Y00737*
X06358*
Y00736*
X06357*
Y00736*
X06356*
Y00735*
X06355*
Y00735*
X06354*
Y00734*
X06352*
Y00734*
X0635*
Y00733*
X06349*
Y00733*
X06348*
Y00732*
X06346*
Y00732*
X06344*
Y00731*
X06343*
Y0073*
X06341*
Y0073*
X06339*
Y00729*
X06338*
Y00729*
X06336*
Y00728*
X06334*
Y00728*
X06332*
Y00727*
X0633*
Y00727*
X06328*
Y00726*
X06325*
Y00726*
X06323*
Y00725*
X06321*
Y00725*
X06318*
Y00724*
X06315*
Y00723*
X06311*
Y00723*
X06308*
Y00722*
X06304*
Y00722*
X06298*
Y00721*
X06292*
Y00721*
X06291*
Y00721*
X0629*
Y00721*
X06269*
Y00721*
X06261*
Y00722*
X06256*
Y00722*
X06252*
Y00723*
X06248*
Y00723*
X06245*
Y00724*
X06242*
Y00725*
X06239*
Y00725*
X06236*
Y00726*
X06234*
Y00726*
X06232*
Y00727*
X0623*
Y00727*
X06228*
Y00728*
X06225*
Y00728*
X06224*
Y00729*
X06222*
Y00729*
X0622*
Y0073*
X06218*
Y0073*
X06217*
Y00731*
X06215*
Y00732*
X06213*
Y00732*
X06212*
Y00733*
X0621*
Y00733*
X06209*
Y00734*
X06208*
Y00734*
X06206*
Y00735*
X06205*
Y00735*
X06203*
Y00736*
X06202*
Y00736*
X06201*
Y00737*
X06199*
Y00737*
X06198*
Y00738*
X06197*
Y00739*
X06196*
Y00739*
X06195*
Y0074*
X06193*
Y0074*
X06192*
Y00741*
X06191*
Y00741*
X0619*
Y00742*
X06189*
Y00742*
X06188*
Y00743*
X06187*
Y00743*
X06186*
Y00744*
X06185*
Y00745*
X06184*
Y00745*
X06183*
Y00746*
X06182*
Y00746*
X06181*
Y00747*
X0618*
Y00747*
X06179*
Y00748*
X06178*
Y00748*
X06177*
Y00749*
X06176*
Y00749*
X06175*
Y0075*
X06175*
Y0075*
X06173*
Y00751*
X06173*
Y00752*
X06172*
Y00752*
X06171*
Y00753*
X0617*
Y00753*
X06169*
Y00754*
X06169*
Y00754*
X06168*
Y00755*
X06167*
Y00755*
X06166*
Y00756*
X06165*
Y00756*
X06164*
Y00757*
X06164*
Y00757*
X06163*
Y00758*
X06162*
Y00759*
X06162*
Y00759*
X06161*
Y0076*
X0616*
Y0076*
X06159*
Y00761*
X06158*
Y00761*
X06158*
Y00762*
X06157*
Y00762*
X06156*
Y00763*
X06156*
Y00763*
X06155*
Y00764*
X06154*
Y00765*
X06153*
Y00765*
X06153*
Y00766*
X06152*
Y00766*
X06151*
Y00767*
X06151*
Y00767*
X0615*
Y00768*
X0615*
Y00768*
X06149*
Y00769*
X06148*
Y00769*
X06148*
Y0077*
X06147*
Y0077*
X06146*
Y00771*
X06146*
Y00772*
X06145*
Y00772*
X06145*
Y00773*
X06144*
Y00773*
X06143*
Y00774*
X06143*
Y00774*
X06142*
Y00775*
X06142*
Y00775*
X06141*
Y00776*
X06141*
Y00776*
X0614*
Y00777*
X06139*
Y00777*
X06139*
Y00778*
X06138*
Y00779*
X06138*
Y00779*
X06137*
Y0078*
X06137*
Y0078*
X06136*
Y00781*
X06136*
Y00781*
X06135*
Y00782*
X06135*
Y00782*
X06134*
Y00783*
X06133*
Y00783*
X06133*
Y00784*
X06132*
Y00785*
X06132*
Y00785*
X06131*
Y00786*
X06131*
Y00786*
X0613*
Y00787*
X0613*
Y00787*
X06129*
Y00788*
Y00788*
X06129*
Y00789*
X06128*
Y00789*
X06128*
Y0079*
X06127*
Y0079*
X06126*
Y00791*
X06126*
Y00792*
X06125*
Y00792*
Y00793*
X06125*
Y00793*
X06124*
Y00794*
X06124*
Y00794*
X06123*
Y00795*
X06123*
Y00795*
Y00796*
X06122*
Y00796*
X06122*
Y00797*
X06121*
Y00797*
X06121*
Y00798*
Y00799*
X0612*
Y00799*
X06119*
Y008*
X06119*
Y008*
Y00801*
X06118*
Y00801*
X06118*
Y00802*
X06117*
Y00802*
Y00803*
X06117*
Y00803*
X06116*
Y00804*
X06116*
Y00805*
Y00805*
X06115*
Y00806*
X06115*
Y00806*
X06114*
Y00807*
Y00807*
X06113*
Y00808*
X06113*
Y00808*
Y00809*
X06112*
Y00809*
X06112*
Y0081*
Y0081*
X06111*
Y00811*
X06111*
Y00812*
Y00812*
X0611*
Y00813*
X0611*
Y00813*
Y00814*
X06109*
Y00814*
X06109*
Y00815*
Y00815*
X06108*
Y00816*
Y00816*
X06108*
Y00817*
X06107*
Y00817*
Y00818*
X06106*
Y00819*
X06106*
Y00819*
Y0082*
X06105*
Y0082*
Y00821*
X06105*
Y00821*
Y00822*
X06104*
Y00822*
X06104*
Y00823*
Y00823*
X06103*
Y00824*
Y00825*
X06103*
Y00825*
Y00826*
X06102*
Y00826*
X06102*
Y00827*
Y00827*
X06101*
Y00828*
Y00828*
X06101*
Y00829*
Y00829*
X061*
Y0083*
Y0083*
X06099*
Y00831*
Y00832*
X06099*
Y00832*
Y00833*
X06098*
Y00833*
Y00834*
X06098*
Y00834*
Y00835*
X06097*
Y00835*
Y00836*
X06097*
Y00836*
Y00837*
X06096*
Y00837*
Y00838*
X06096*
Y00839*
Y00839*
X06095*
Y0084*
Y0084*
Y00841*
X06095*
Y00841*
Y00842*
X06094*
Y00842*
Y00843*
X06093*
Y00843*
Y00844*
Y00845*
X06093*
Y00845*
Y00846*
X06092*
Y00846*
Y00847*
X06092*
Y00847*
Y00848*
Y00848*
X06091*
Y00849*
Y00849*
X06091*
Y0085*
Y0085*
Y00851*
X0609*
Y00852*
Y00852*
Y00853*
X0609*
Y00853*
Y00854*
X06089*
Y00854*
Y00855*
Y00855*
X06089*
Y00856*
Y00856*
Y00857*
X06088*
Y00857*
Y00858*
Y00859*
X06088*
Y00859*
Y0086*
Y0086*
X06087*
Y00861*
Y00861*
Y00862*
X06086*
Y00862*
Y00863*
Y00863*
X06086*
Y00864*
Y00865*
Y00865*
X06085*
Y00866*
Y00866*
Y00867*
Y00867*
X06085*
Y00868*
Y00868*
Y00869*
X06084*
Y00869*
Y0087*
Y0087*
Y00871*
X06084*
Y00872*
Y00872*
Y00873*
Y00873*
X06083*
Y00874*
Y00874*
Y00875*
Y00875*
X06083*
Y00876*
Y00876*
Y00877*
Y00877*
X06082*
Y00878*
Y00879*
Y00879*
Y0088*
Y0088*
X06082*
Y00881*
Y00881*
Y00882*
Y00882*
Y00883*
X06081*
Y00883*
Y00884*
Y00885*
Y00885*
Y00886*
X06081*
Y00886*
Y00887*
Y00887*
Y00888*
Y00888*
X0608*
Y00889*
Y00889*
Y0089*
Y0089*
Y00891*
Y00892*
X06079*
Y00892*
Y00893*
Y00893*
Y00894*
Y00894*
Y00895*
Y00895*
X06079*
Y00896*
Y00896*
Y00897*
Y00897*
Y00898*
Y00899*
Y00899*
Y009*
X06078*
Y009*
Y00901*
Y00901*
Y00902*
Y00902*
Y00903*
Y00903*
Y00904*
Y00905*
Y00905*
X06078*
Y00906*
Y00906*
Y00907*
Y00907*
Y00908*
Y00908*
Y00909*
Y00909*
Y0091*
Y0091*
Y00911*
Y00912*
Y00912*
Y00913*
Y00913*
Y00914*
X06077*
Y00914*
Y00915*
Y00915*
Y00916*
Y00916*
Y00917*
G37*
%LNtimingcard_pcb-3*%
%LPD*%
G36*
X06524Y00888D02*
X06525D01*
Y00888*
Y00887*
Y00887*
Y00886*
Y00886*
Y00885*
Y00885*
Y00884*
Y00883*
Y00883*
Y00882*
Y00882*
Y00881*
Y00881*
Y0088*
Y0088*
Y00879*
Y00879*
Y00878*
Y00877*
Y00877*
Y00876*
Y00876*
Y00875*
Y00875*
Y00874*
Y00874*
Y00873*
Y00873*
Y00872*
Y00872*
Y00871*
Y0087*
Y0087*
Y00869*
Y00869*
Y00868*
Y00868*
Y00867*
Y00867*
Y00866*
Y00866*
Y00865*
Y00865*
Y00864*
Y00863*
Y00863*
Y00862*
Y00862*
Y00861*
Y00861*
Y0086*
Y0086*
Y00859*
Y00859*
Y00858*
Y00857*
Y00857*
Y00856*
Y00856*
Y00855*
Y00855*
Y00854*
Y00854*
Y00853*
Y00853*
Y00852*
Y00852*
Y00851*
Y0085*
Y0085*
Y00849*
Y00849*
Y00848*
Y00848*
Y00847*
Y00847*
Y00846*
Y00846*
Y00845*
Y00845*
Y00844*
Y00843*
Y00843*
Y00842*
Y00842*
Y00841*
Y00841*
Y0084*
Y0084*
Y00839*
Y00839*
Y00838*
Y00837*
Y00837*
Y00836*
Y00836*
Y00835*
Y00835*
Y00834*
Y00834*
Y00833*
Y00833*
Y00832*
Y00832*
Y00831*
Y0083*
Y0083*
Y00829*
Y00829*
Y00828*
X06485*
Y00829*
Y00829*
Y0083*
Y0083*
Y00831*
Y00832*
Y00832*
Y00833*
Y00833*
Y00834*
Y00834*
Y00835*
Y00835*
Y00836*
Y00836*
Y00837*
Y00837*
Y00838*
Y00839*
Y00839*
Y0084*
Y0084*
Y00841*
Y00841*
Y00842*
Y00842*
Y00843*
Y00843*
Y00844*
Y00845*
Y00845*
Y00846*
Y00846*
Y00847*
Y00847*
Y00848*
Y00848*
Y00849*
Y00849*
Y0085*
Y0085*
Y00851*
Y00852*
Y00852*
Y00853*
Y00853*
Y00854*
Y00854*
Y00855*
Y00855*
Y00856*
Y00856*
Y00857*
Y00857*
Y00858*
Y00859*
Y00859*
Y0086*
Y0086*
Y00861*
Y00861*
Y00862*
Y00862*
Y00863*
Y00863*
Y00864*
Y00865*
Y00865*
Y00866*
Y00866*
Y00867*
Y00867*
Y00868*
Y00868*
Y00869*
Y00869*
Y0087*
Y0087*
Y00871*
Y00872*
Y00872*
Y00873*
Y00873*
Y00874*
Y00874*
Y00875*
Y00875*
Y00876*
Y00876*
Y00877*
Y00877*
Y00878*
Y00879*
Y00879*
Y0088*
Y0088*
Y00881*
Y00881*
Y00882*
Y00882*
Y00883*
Y00883*
Y00884*
Y00885*
Y00885*
Y00886*
Y00886*
Y00887*
Y00887*
Y00888*
Y00888*
X06486*
Y00889*
X06487*
Y00888*
X06522*
Y00889*
X06522*
Y00888*
X06523*
Y00889*
X06524*
Y00888*
G37*
G36*
X0641Y00889D02*
Y00889D01*
Y00888*
Y00888*
Y00887*
Y00887*
Y00886*
Y00886*
Y00885*
Y00885*
Y00884*
Y00883*
Y00883*
Y00882*
Y00882*
Y00881*
Y00881*
Y0088*
Y0088*
Y00879*
Y00879*
Y00878*
Y00877*
Y00877*
Y00876*
Y00876*
Y00875*
Y00875*
Y00874*
Y00874*
Y00873*
Y00873*
Y00872*
Y00872*
Y00871*
Y0087*
Y0087*
Y00869*
Y00869*
Y00868*
Y00868*
Y00867*
Y00867*
Y00866*
Y00866*
Y00865*
Y00865*
Y00864*
Y00863*
Y00863*
Y00862*
Y00862*
Y00861*
X06369*
Y00862*
Y00862*
Y00863*
Y00863*
Y00864*
Y00865*
Y00865*
Y00866*
Y00866*
Y00867*
Y00867*
Y00868*
Y00868*
Y00869*
Y00869*
Y0087*
Y0087*
Y00871*
Y00872*
Y00872*
Y00873*
Y00873*
Y00874*
Y00874*
Y00875*
Y00875*
Y00876*
Y00876*
Y00877*
Y00877*
Y00878*
Y00879*
Y00879*
Y0088*
Y0088*
Y00881*
Y00881*
Y00882*
Y00882*
Y00883*
Y00883*
Y00884*
Y00885*
Y00885*
Y00886*
Y00886*
Y00887*
Y00887*
Y00888*
Y00888*
Y00889*
Y00889*
Y0089*
X0641*
Y00889*
G37*
G54D26*
X02545Y00137D03*
X02466D03*
X02348D03*
X0282D03*
X01915D03*
X02033D03*
X02663D03*
X02702D03*
X0286D03*
X02978D03*
X0219D03*
X01994D03*
X01954D03*
X03017D03*
X02309D03*
X02112D03*
X02151D03*
X02387D03*
X02427D03*
X02584D03*
X02624D03*
X02742D03*
X02781D03*
X02899D03*
X02938D03*
X02505D03*
X02072D03*
X01797D03*
X01836D03*
X01875D03*
X03096D03*
G54D27*
X03057Y00157D03*
G54D28*
X0415Y03603D03*
X04204D03*
X04638Y04204D03*
X04692D03*
X03532Y02797D03*
X03477D03*
X0609Y03556D03*
X06035D03*
X06842Y01816D03*
X06897D03*
X06736Y01818D03*
X0679D03*
X06311Y0246D03*
X06365D03*
X04112Y03701D03*
X04167D03*
X05161Y04208D03*
X05216D03*
X04638Y04149D03*
X04692D03*
G54D29*
X00966Y0072D03*
X00907D03*
X05159Y04153D03*
X05218D03*
X00966Y01216D03*
X00907D03*
X00959Y01747D03*
X009D03*
X0097Y02275D03*
X00911D03*
G54D30*
X00653Y01894D03*
Y0201D03*
Y02422D03*
Y02538D03*
Y00847D03*
Y00963D03*
Y01375D03*
Y01491D03*
G54D31*
X00713Y01952D03*
Y0248D03*
Y00905D03*
Y01433D03*
G54D32*
X01248Y04052D03*
Y04105D03*
X01047Y04052D03*
Y04105D03*
X00846Y04052D03*
Y04105D03*
X00641Y04052D03*
Y04105D03*
G54D33*
X02209Y03716D03*
Y03645D03*
X04339Y02851D03*
Y0278D03*
X06334Y02181D03*
Y0211D03*
X06659Y02095D03*
Y02166D03*
X06275Y02822D03*
Y02893D03*
X06362Y02822D03*
Y02893D03*
X04104Y03841D03*
Y0377D03*
X02639Y03606D03*
Y03535D03*
X03693Y03117D03*
Y03188D03*
X04064Y02851D03*
Y0278D03*
X03959Y02851D03*
Y0278D03*
X04234Y02851D03*
Y0278D03*
G54D34*
X06679Y0242D03*
Y02802D03*
X06319Y0146D03*
Y01842D03*
G54D35*
X06687Y01611D03*
X06632D03*
X06687Y01671D03*
X06632D03*
X06687Y01721D03*
X06632D03*
X06687Y01776D03*
X06632D03*
X06152Y02171D03*
X06097D03*
X06847Y02096D03*
X06902D03*
X0372Y00645D03*
X03665D03*
X06314Y02673D03*
X0637D03*
X06314Y02606D03*
X0637D03*
X06314Y02535D03*
X0637D03*
X06314Y0274D03*
X0637D03*
X05622Y03358D03*
X05677D03*
G54D36*
X04394Y03929D03*
X04439D03*
G54D37*
X03125Y02787D03*
Y02732D03*
X03358Y02791D03*
Y02736D03*
X04523Y03846D03*
Y03791D03*
X04454Y03033D03*
Y03088D03*
X04394Y03033D03*
Y03088D03*
X04334Y03033D03*
Y03088D03*
X04274Y03033D03*
Y03088D03*
X04219Y03033D03*
Y03088D03*
X04164Y03033D03*
Y03088D03*
X04109Y03033D03*
Y03088D03*
X03771Y03137D03*
Y03082D03*
X0272Y03598D03*
Y03543D03*
X02139Y03653D03*
Y03708D03*
X06586Y03059D03*
Y03003D03*
G54D38*
X04375Y0386D03*
X0445D03*
Y03776D03*
X04413D03*
G54D39*
X04375Y03776D03*
G54D40*
X0371Y03786D03*
X03659D03*
X0371Y03861D03*
X03659D03*
G54D41*
X06064Y02387D03*
Y02334D03*
X06939Y01879D03*
Y01932D03*
G54D42*
X02212Y01037D03*
X0298Y02357D03*
X02586Y02517D03*
X02488D03*
X02389D03*
X02291D03*
X02881Y02357D03*
X02783D03*
X02685D03*
X02586D03*
X02488D03*
X02389D03*
X02291D03*
X0294D03*
X0296D03*
X02901D03*
X02921D03*
X02842D03*
X02862D03*
X02803D03*
X02822D03*
X02744D03*
X02763D03*
X02704D03*
X02724D03*
X02645D03*
X02665D03*
X02606D03*
X02625D03*
X02547D03*
X02566D03*
X02507D03*
X02527D03*
X02448D03*
X02468D03*
X02409D03*
X02429D03*
X0235D03*
X0237D03*
X02212Y02517D03*
X02232D03*
Y02357D03*
X02212D03*
X02251Y02517D03*
X02271D03*
X02409D03*
X02429D03*
X0235D03*
X0237D03*
X02507D03*
X02527D03*
X02448D03*
X02468D03*
X02606D03*
X02547D03*
X02625D03*
X02566D03*
X02251Y02357D03*
X02311D03*
X0233D03*
X02271D03*
X02311Y02517D03*
X0233D03*
X02803Y01037D03*
X02822D03*
X02862Y00877D03*
X02881D03*
X02744D03*
X02763D03*
X02685Y01037D03*
X02704D03*
X02586Y00877D03*
Y01037D03*
X02645Y00877D03*
X02625D03*
X02744Y01037D03*
X02763D03*
X02803Y00877D03*
X02822D03*
X02685D03*
X02704D03*
X02625Y01037D03*
X02645D03*
X02232Y00877D03*
X02429D03*
X0237D03*
X0235D03*
X0233D03*
X02291D03*
X02389D03*
X02488D03*
X02527D03*
X02547D03*
X02566D03*
X02448D03*
X02468D03*
X02251D03*
X02271D03*
X02566Y01037D03*
X0237D03*
X02389D03*
X02429D03*
X02468D03*
X02488D03*
X02448D03*
X02291D03*
X02271D03*
X02251D03*
X02232D03*
X0235D03*
X0233D03*
X02547D03*
X02527D03*
X02862D03*
X02881D03*
X02921Y00877D03*
Y01037D03*
X0294Y00877D03*
Y01037D03*
X0298Y00877D03*
Y01037D03*
X0296D03*
Y00877D03*
X02901Y01037D03*
X02842D03*
X02783D03*
X02724D03*
X02665D03*
X02606D03*
X02507D03*
X02409D03*
X02311D03*
X02901Y00877D03*
X02842D03*
X02783D03*
X02724D03*
X02665D03*
X02606D03*
X02507D03*
X02409D03*
X02311D03*
X02212D03*
X02645Y02517D03*
X02665D03*
X02685D03*
X02704D03*
X02724D03*
X02744D03*
X02763D03*
X02783D03*
X02803D03*
X02822D03*
X02842D03*
X02862D03*
X02881D03*
X02901D03*
X02921D03*
X0294D03*
X0296D03*
X0298D03*
G54D43*
X01696Y01262D03*
X0357D03*
X01696Y02142D03*
X0357D03*
G54D44*
X02156Y02437D03*
Y00957D03*
X03036D03*
Y02437D03*
G54D45*
X03491Y01397D03*
Y01377D03*
Y01456D03*
Y01476D03*
Y01771D03*
Y01495D03*
Y01791D03*
Y01889D03*
Y0185D03*
Y01869D03*
Y0183D03*
X03651Y01869D03*
Y01889D03*
Y01928D03*
X03491Y01338D03*
Y01358D03*
X03651Y01791D03*
Y01771D03*
Y0185D03*
Y0183D03*
Y01948D03*
Y01988D03*
Y01968D03*
X03491Y01988D03*
Y01968D03*
X03651Y01692D03*
X03491Y01633D03*
Y01673D03*
Y01653D03*
Y01692D03*
X03651Y01732D03*
Y01751D03*
Y01653D03*
Y01574D03*
Y01554D03*
Y01673D03*
Y01633D03*
X03491Y01928D03*
Y01554D03*
Y02007D03*
Y01909D03*
Y0181D03*
Y01712D03*
Y01613D03*
Y01515D03*
Y01417D03*
X03651Y02007D03*
Y01909D03*
Y0181D03*
Y01712D03*
Y01613D03*
Y01515D03*
Y01417D03*
X03491Y01948D03*
X03651Y01594D03*
X03491Y01535D03*
X03651Y01495D03*
Y01476D03*
Y01456D03*
Y01436D03*
Y01397D03*
Y01377D03*
Y01358D03*
Y01338D03*
X03491Y01318D03*
X03651D03*
X03491Y01732D03*
Y01751D03*
X03651Y01535D03*
X03491Y01574D03*
Y01594D03*
Y01436D03*
Y02086D03*
Y02066D03*
Y02047D03*
Y02027D03*
X03651Y02086D03*
Y02066D03*
Y02047D03*
Y02027D03*
X01776Y01633D03*
Y01614D03*
Y01869D03*
Y02027D03*
Y01909D03*
Y0183D03*
Y01948D03*
Y01732D03*
Y01771D03*
X01616Y01928D03*
Y0185D03*
Y01909D03*
Y02027D03*
X01776Y02007D03*
Y01968D03*
Y01456D03*
Y01673D03*
X01616Y01869D03*
Y01968D03*
X01776Y01928D03*
Y0185D03*
Y0181D03*
Y01653D03*
X01616Y02007D03*
X01776Y01751D03*
Y01712D03*
X01616Y01948D03*
X01776Y01554D03*
Y01574D03*
X01616Y01515D03*
Y01456D03*
Y0181D03*
Y0183D03*
X01776Y01436D03*
X01616Y01358D03*
X01776Y01338D03*
X01616Y01574D03*
Y01436D03*
Y01535D03*
Y01554D03*
Y01614D03*
Y01732D03*
Y01673D03*
Y01377D03*
Y01476D03*
Y01417D03*
Y01751D03*
X01776Y01358D03*
X01616Y01338D03*
Y01633D03*
Y01771D03*
X01776Y01377D03*
Y01318D03*
Y01417D03*
X01616Y01318D03*
X01776Y01476D03*
X01616Y01712D03*
Y01653D03*
X01776Y01515D03*
X01616Y02047D03*
X01776D03*
Y01397D03*
Y01495D03*
Y01594D03*
Y01692D03*
Y01791D03*
Y01889D03*
Y01988D03*
X01616Y01397D03*
Y01495D03*
Y01594D03*
Y01692D03*
Y01791D03*
Y01889D03*
Y01988D03*
Y02086D03*
X01776D03*
Y02066D03*
Y01535D03*
X01616Y02066D03*
G54D46*
X03111Y02937D03*
Y02987D03*
Y03037D03*
Y03087D03*
Y03137D03*
Y03187D03*
Y03237D03*
Y03287D03*
X02756Y02937D03*
Y02987D03*
Y03037D03*
Y03087D03*
Y03137D03*
Y03187D03*
Y03237D03*
Y03287D03*
G54D47*
X02199Y04275D03*
X02465D03*
G54D48*
X02281Y0417D03*
X02306D03*
X02332D03*
X02358D03*
X02383D03*
G54D49*
X0243Y04173D03*
X02234D03*
G54D50*
X02377Y04275D03*
G54D51*
X02271Y04275D03*
G54D52*
X03808Y04023D03*
X03839D03*
X03871D03*
X03902D03*
X03934D03*
G54D53*
X03696Y04244D03*
Y04027D03*
X04046D03*
Y04244D03*
G54D54*
X03495Y0375D03*
X03444D03*
X03469Y03661D03*
X0286Y0375D03*
X02809D03*
X02834Y03661D03*
X02745Y0375D03*
X02694D03*
X02719Y03661D03*
X0327Y0375D03*
X03219D03*
X03244Y03661D03*
G54D55*
X01631Y04199D03*
Y04174D03*
Y04149D03*
Y04124D03*
Y04099D03*
Y04074D03*
Y04049D03*
Y04024D03*
X01846Y04199D03*
Y04174D03*
Y04149D03*
Y04124D03*
Y04099D03*
Y04074D03*
Y04049D03*
Y04024D03*
X03772Y03858D03*
Y03833D03*
Y03808D03*
Y03783D03*
Y03758D03*
Y03733D03*
Y03708D03*
Y03683D03*
X03987Y03858D03*
Y03833D03*
Y03808D03*
Y03783D03*
Y03758D03*
Y03733D03*
Y03708D03*
Y03683D03*
G54D56*
X06157Y02241D03*
Y02291D03*
Y02341D03*
Y02391D03*
X06352D03*
Y02341D03*
Y02291D03*
Y02241D03*
X06832Y02031D03*
Y01981D03*
Y01931D03*
Y01881D03*
X06637D03*
Y01931D03*
Y01981D03*
Y02031D03*
G54D57*
X06197Y03701D03*
X06341D03*
X05887D03*
X06031D03*
X06346Y03566D03*
X06202D03*
G54D58*
X06726Y03294D03*
X06943D03*
Y03168D03*
X06726D03*
G54D59*
X03569Y03385D03*
G54D60*
X03392Y03395D03*
X0351Y03206D03*
X03333D03*
Y03395D03*
X03569Y03206D03*
X0351Y03395D03*
X03451D03*
X03392Y03206D03*
X03451D03*
G54D61*
X03525Y02995D03*
Y02948D03*
X03444D03*
Y02995D03*
G54D62*
X03484Y03051D03*
Y02892D03*
G54D63*
X03531Y02892D03*
Y03051D03*
X03438Y02892D03*
Y03051D03*
G54D64*
X02944Y03951D03*
Y04221D03*
X03044Y03951D03*
Y04221D03*
X03144Y03951D03*
Y04221D03*
X03244Y03951D03*
Y04221D03*
X03344Y03951D03*
Y04221D03*
G54D65*
X03349Y03745D03*
Y03666D03*
X02944Y03745D03*
Y03666D03*
X03044Y03745D03*
Y03666D03*
X03144Y03745D03*
Y03666D03*
G54D66*
X05091Y04206D03*
X04957D03*
X04566D03*
X04432D03*
G54D67*
X04068Y01779D03*
X03911D03*
X04068Y01759D03*
X03911D03*
X04068Y01739D03*
X03911D03*
X04068Y01719D03*
X03911D03*
X04068Y01699D03*
X03911D03*
X04068Y01679D03*
X03911D03*
X04068Y01659D03*
X03911D03*
X04068Y01639D03*
X03911D03*
X04068Y01619D03*
X03911D03*
Y01599D03*
X04068D03*
G54D68*
X06479Y0315D03*
X06459D03*
X0644D03*
X0642D03*
Y03332D03*
X0644D03*
X06459D03*
X06479D03*
G54D69*
X06511Y03152D03*
X06388D03*
Y03172D03*
Y03191D03*
Y03211D03*
Y03231D03*
Y0325D03*
Y0327D03*
Y0329D03*
Y03309D03*
Y03329D03*
X06511D03*
Y03309D03*
Y0329D03*
Y0327D03*
Y0325D03*
Y03231D03*
Y03211D03*
Y03172D03*
Y03191D03*
G54D70*
X04149Y02842D03*
Y02789D03*
X04434Y02842D03*
Y02789D03*
G54D71*
X04909Y02808D03*
Y03961D03*
G54D72*
X00932Y00906D03*
X01157D03*
Y01956D03*
X00932D03*
X01157Y02481D03*
X00932D03*
Y01431D03*
X01157D03*
G54D73*
X01249Y04197D03*
Y04254D03*
X03589Y03909D03*
Y03852D03*
Y03727D03*
Y03784D03*
X00644Y04254D03*
Y04197D03*
X00846Y04254D03*
Y04197D03*
X01048D03*
Y04254D03*
G54D74*
X04039Y03092D03*
Y03029D03*
X06469Y02302D03*
Y02239D03*
X06519Y02017D03*
Y01954D03*
X04194Y03837D03*
Y03774D03*
X03688Y03329D03*
Y03266D03*
X06604Y03327D03*
Y03264D03*
Y03129D03*
Y03192D03*
G54D75*
X03249Y02845D03*
X03229D03*
Y02784D03*
X03249D03*
G54D76*
X03209Y02834D03*
Y02814D03*
Y02795D03*
X03269D03*
Y02814D03*
Y02834D03*
G54D77*
X05812Y03361D03*
X05741D03*
X067Y01421D03*
X06629D03*
X067Y01531D03*
X06629D03*
X0651Y03071D03*
X06439D03*
X03659Y00726D03*
X0373D03*
X01873Y04276D03*
X01802D03*
X04209Y03246D03*
X0428D03*
G54D78*
X04332Y03603D03*
X04275D03*
G54D79*
X06749Y02088D03*
Y02143D03*
X06234Y02128D03*
Y02183D03*
X07Y01878D03*
Y01932D03*
X06003Y02335D03*
Y02389D03*
X02146Y02679D03*
Y02624D03*
X06122Y02433D03*
Y02488D03*
X01933Y04129D03*
Y04074D03*
G54D80*
X02503Y00573D03*
Y00607D03*
X03055Y00573D03*
Y00607D03*
G54D81*
X02509Y0364D03*
Y03483D03*
Y03562D03*
Y03404D03*
X02334Y0364D03*
Y03562D03*
Y03483D03*
Y03404D03*
G54D82*
X01727Y04273D03*
X01664D03*
G54D83*
X01346Y04141D03*
Y04082D03*
Y03978D03*
Y04037D03*
X02151Y04074D03*
Y04015D03*
X02212Y04074D03*
Y04015D03*
X02387Y02958D03*
Y02899D03*
M02*